FILE_TYPE = MACRO_DRAWING;
SET COLOR_WIRE YELLOW;
SET COLOR_PROP ORANGE;
SET COLOR_DOT WHITE;
SET COLOR_ARC YELLOW;
SET COLOR_BODY GREEN;
SET COLOR_NOTE PURPLE;
SET PROP_DISPLAY VALUE;
SET PAGE_NUMBER P155;
FORCEADD GL852GOHY60..1
(125 3825);
FORCEPROP 1 LAST PART_NUMBER AL000852001
J 0
(-195 4572);
DISPLAY 0.723404 (-195 4572);
PAINT GREEN (-195 4572);
DISPLAY INVISIBLE (-195 4572);
FORCEPROP 2 LAST ROOM USB1_BOM1
J 0
(-175 4875);
DISPLAY 1.021277 (-175 4875);
FORCEPROP 2 LAST VALUE GL852G-OHY60
J 0
(-175 4775);
DISPLAY 1.021277 (-175 4775);
FORCEPROP 2 LAST PART_TYPE SMLF
J 0
(-175 4825);
DISPLAY 1.021277 (-175 4825);
FORCEPROP 1 LAST MATERIAL IC
J 0
(-195 4445);
DISPLAY 0.723404 (-195 4445);
PAINT GREEN (-195 4445);
FORCEPROP 1 LAST $LOCATION U268
J 0
(-195 4719);
DISPLAY 0.723404 (-195 4719);
PAINT GREEN (-195 4719);
FORCEPROP 0 LASTPIN (-350 4125) $PN 5
J 2
(-360 4135);
DISPLAY 0.680851 (-360 4135);
PAINT MONO (-360 4135);
FORCEPROP 0 LASTPIN (-350 4075) $PN 9
J 2
(-360 4085);
DISPLAY 0.680851 (-360 4085);
PAINT MONO (-360 4085);
FORCEPROP 0 LASTPIN (-350 4025) $PN 14
J 2
(-360 4035);
DISPLAY 0.680851 (-360 4035);
PAINT MONO (-360 4035);
FORCEPROP 0 LASTPIN (600 3875) $PN 1
J 0
(610 3885);
DISPLAY 0.680851 (610 3885);
PAINT MONO (610 3885);
FORCEPROP 0 LASTPIN (600 3775) $PN 3
J 0
(610 3785);
DISPLAY 0.680851 (610 3785);
PAINT MONO (610 3785);
FORCEPROP 0 LASTPIN (600 3675) $PN 6
J 0
(610 3685);
DISPLAY 0.680851 (610 3685);
PAINT MONO (610 3685);
FORCEPROP 0 LASTPIN (600 3575) $PN 12
J 0
(610 3585);
DISPLAY 0.680851 (610 3585);
PAINT MONO (610 3585);
FORCEPROP 0 LASTPIN (600 3475) $PN 15
J 0
(610 3485);
DISPLAY 0.680851 (610 3485);
PAINT MONO (610 3485);
FORCEPROP 0 LASTPIN (600 3925) $PN 2
J 0
(610 3935);
DISPLAY 0.680851 (610 3935);
PAINT MONO (610 3935);
FORCEPROP 0 LASTPIN (600 3825) $PN 4
J 0
(610 3835);
DISPLAY 0.680851 (610 3835);
PAINT MONO (610 3835);
FORCEPROP 0 LASTPIN (600 3725) $PN 7
J 0
(610 3735);
DISPLAY 0.680851 (610 3735);
PAINT MONO (610 3735);
FORCEPROP 0 LASTPIN (600 3625) $PN 13
J 0
(610 3635);
DISPLAY 0.680851 (610 3635);
PAINT MONO (610 3635);
FORCEPROP 0 LASTPIN (600 3525) $PN 16
J 0
(610 3535);
DISPLAY 0.680851 (610 3535);
PAINT MONO (610 3535);
FORCEPROP 0 LASTPIN (-350 3925) $PN 21
J 2
(-360 3935);
DISPLAY 0.680851 (-360 3935);
PAINT MONO (-360 3935);
FORCEPROP 0 LASTPIN (-350 3775) $PN 25
J 2
(-360 3785);
DISPLAY 0.680851 (-360 3785);
PAINT MONO (-360 3785);
FORCEPROP 0 LASTPIN (-350 3725) $PN 24
J 2
(-360 3735);
DISPLAY 0.680851 (-360 3735);
PAINT MONO (-360 3735);
FORCEPROP 0 LASTPIN (-350 3675) $PN 20
J 2
(-360 3685);
DISPLAY 0.680851 (-360 3685);
PAINT MONO (-360 3685);
FORCEPROP 0 LASTPIN (-350 3625) $PN 19
J 2
(-360 3635);
DISPLAY 0.680851 (-360 3635);
PAINT MONO (-360 3635);
FORCEPROP 0 LASTPIN (-350 3325) $PN 23
J 2
(-360 3335);
DISPLAY 0.680851 (-360 3335);
PAINT MONO (-360 3335);
FORCEPROP 0 LASTPIN (-350 3375) $PN 22
J 2
(-360 3385);
DISPLAY 0.680851 (-360 3385);
PAINT MONO (-360 3385);
FORCEPROP 0 LASTPIN (-350 3425) $PN 17
J 2
(-360 3435);
DISPLAY 0.680851 (-360 3435);
PAINT MONO (-360 3435);
FORCEPROP 0 LASTPIN (-350 3475) $PN 8
J 2
(-360 3485);
DISPLAY 0.680851 (-360 3485);
PAINT MONO (-360 3485);
FORCEPROP 0 LASTPIN (600 4325) $PN 26
J 0
(610 4335);
DISPLAY 0.680851 (610 4335);
PAINT MONO (610 4335);
FORCEPROP 0 LASTPIN (600 4275) $PN 18
J 0
(610 4285);
DISPLAY 0.680851 (610 4285);
PAINT MONO (610 4285);
FORCEPROP 0 LASTPIN (600 3325) $PN TH
J 0
(610 3335);
DISPLAY 0.680851 (610 3335);
PAINT MONO (610 3335);
FORCEPROP 0 LASTPIN (-350 4325) $PN 27
J 2
(-360 4335);
DISPLAY 0.680851 (-360 4335);
PAINT MONO (-360 4335);
FORCEPROP 0 LASTPIN (-350 4225) $PN 28
J 2
(-360 4235);
DISPLAY 0.680851 (-360 4235);
PAINT MONO (-360 4235);
FORCEPROP 0 LASTPIN (600 4125) $PN 10
J 0
(615 4135);
DISPLAY 0.680851 (615 4135);
PAINT MONO (615 4135);
FORCEPROP 0 LASTPIN (600 4075) $PN 11
J 0
(610 4085);
DISPLAY 0.680851 (610 4085);
PAINT MONO (610 4085);
FORCEPROP 1 LAST PATH I100
J 0
(125 3825);
DISPLAY 0.723404 (125 3825);
PAINT GREEN (125 3825);
DISPLAY INVISIBLE (125 3825);
FORCEPROP 2 LAST CDS_LIB pure_quanta
J 0
(125 3825);
DISPLAY INVISIBLE (125 3825);
FORCEPROP 1 LAST CDS_LMAN_SYM_OUTLINE -325,600,325,-600
J 0
(125 3825);
DISPLAY 0.468085 (125 3825);
PAINT GREEN (125 3825);
DISPLAY INVISIBLE (125 3825);
FORCEPROP 1 LAST NEEDS_NO_SIZE TRUE
J 0
(125 3825);
DISPLAY 0.723404 (125 3825);
PAINT GREEN (125 3825);
DISPLAY INVISIBLE (125 3825);
FORCEPROP 0 LAST CDS_LOCATION U268
J 0
(-175 4875);
DISPLAY 1.021277 (-175 4875);
DISPLAY INVISIBLE (-175 4875);
FORCEPROP 0 LAST $SEC 1
J 0
(-175 4875);
DISPLAY 0.680851 (-175 4875);
PAINT MONO (-175 4875);
DISPLAY INVISIBLE (-175 4875);
FORCEPROP 0 LAST CDS_SEC 1
J 0
(-175 4875);
DISPLAY 1.021277 (-175 4875);
DISPLAY INVISIBLE (-175 4875);
FORCEADD UNIVERSAL_GND..1
(3700 4325);
FORCEPROP 3 LASTPIN (3700 4375) SIG_NAME GND\g
J 0
(3710 4385);
DISPLAY 0.659574 (3710 4385);
PAINT MONO (3710 4385);
DISPLAY INVISIBLE (3710 4385);
FORCEPROP 1 LAST PATH I115
J 0
(3775 4325);
DISPLAY 0.872340 (3775 4325);
PAINT AQUA (3775 4325);
DISPLAY INVISIBLE (3775 4325);
FORCEPROP 1 LAST HDL_POWER GND
J 1
(3725 4250);
DISPLAY 0.872340 (3725 4250);
PAINT GREEN (3725 4250);
DISPLAY INVISIBLE (3725 4250);
FORCEPROP 2 LAST CDS_LIB logical_power
J 0
(3700 4325);
DISPLAY INVISIBLE (3700 4325);
FORCEADD UNIVERSAL_GND..1
(4350 4325);
FORCEPROP 3 LASTPIN (4350 4375) SIG_NAME GND\g
J 0
(4360 4385);
DISPLAY 0.659574 (4360 4385);
PAINT MONO (4360 4385);
DISPLAY INVISIBLE (4360 4385);
FORCEPROP 1 LAST PATH I116
J 0
(4425 4325);
DISPLAY 0.872340 (4425 4325);
PAINT AQUA (4425 4325);
DISPLAY INVISIBLE (4425 4325);
FORCEPROP 1 LAST HDL_POWER GND
J 1
(4375 4250);
DISPLAY 0.872340 (4375 4250);
PAINT GREEN (4375 4250);
DISPLAY INVISIBLE (4375 4250);
FORCEPROP 2 LAST CDS_LIB logical_power
J 0
(4350 4325);
DISPLAY INVISIBLE (4350 4325);
FORCEADD UNIVERSAL_GND..1
(4475 4150);
FORCEPROP 3 LASTPIN (4475 4200) SIG_NAME GND\g
J 0
(4485 4210);
DISPLAY 0.659574 (4485 4210);
PAINT MONO (4485 4210);
DISPLAY INVISIBLE (4485 4210);
FORCEPROP 1 LAST PATH I117
J 0
(4550 4150);
DISPLAY 0.872340 (4550 4150);
PAINT AQUA (4550 4150);
DISPLAY INVISIBLE (4550 4150);
FORCEPROP 1 LAST HDL_POWER GND
J 1
(4500 4075);
DISPLAY 0.872340 (4500 4075);
PAINT GREEN (4500 4075);
DISPLAY INVISIBLE (4500 4075);
FORCEPROP 2 LAST CDS_LIB logical_power
J 0
(4475 4150);
DISPLAY INVISIBLE (4475 4150);
FORCEADD UNIVERSAL_GND..1
(3475 4150);
FORCEPROP 3 LASTPIN (3475 4200) SIG_NAME GND\g
J 0
(3485 4210);
DISPLAY 0.659574 (3485 4210);
PAINT MONO (3485 4210);
DISPLAY INVISIBLE (3485 4210);
FORCEPROP 1 LAST PATH I118
J 0
(3550 4150);
DISPLAY 0.872340 (3550 4150);
PAINT AQUA (3550 4150);
DISPLAY INVISIBLE (3550 4150);
FORCEPROP 1 LAST HDL_POWER GND
J 1
(3500 4075);
DISPLAY 0.872340 (3500 4075);
PAINT GREEN (3500 4075);
DISPLAY INVISIBLE (3500 4075);
FORCEPROP 2 LAST CDS_LIB logical_power
J 0
(3475 4150);
DISPLAY INVISIBLE (3475 4150);
FORCEADD UNIVERSAL_GND..1
R 1
(2025 4275);
FORCEPROP 3 LASTPIN (1975 4275) SIG_NAME GND\g
J 0
(1985 4285);
DISPLAY 0.659574 (1985 4285);
PAINT MONO (1985 4285);
DISPLAY INVISIBLE (1985 4285);
FORCEPROP 1 LAST PATH I122
R 1
J 0
(2025 4350);
DISPLAY 0.872340 (2025 4350);
PAINT AQUA (2025 4350);
DISPLAY INVISIBLE (2025 4350);
FORCEPROP 1 LAST HDL_POWER GND
R 1
J 1
(2100 4300);
DISPLAY 0.872340 (2100 4300);
PAINT GREEN (2100 4300);
DISPLAY INVISIBLE (2100 4300);
FORCEPROP 2 LAST CDS_LIB logical_power
J 0
(2025 4275);
DISPLAY INVISIBLE (2025 4275);
FORCEADD OFFPAGE..6
R 2
(1675 3825);
PAINT AQUA (1675 3825);
FORCEPROP 2 LAST $XR0 152 
J 0
(1889 3825);
DISPLAY 0.638298 (1889 3825);
PAINT MONO (1889 3825);
FORCEPROP 2 LAST PATH I133
J 0
(2000 3875);
DISPLAY 1.021277 (2000 3875);
DISPLAY INVISIBLE (2000 3875);
FORCEPROP 1 LAST COMMENT_BODY TRUE
J 2
(1575 3750);
DISPLAY 1.170213 (1575 3750);
PAINT GREEN (1575 3750);
DISPLAY INVISIBLE (1575 3750);
FORCEPROP 1 LAST OFFPAGE TRUE
J 2
(1350 3700);
DISPLAY 0.872340 (1350 3700);
PAINT AQUA (1350 3700);
DISPLAY INVISIBLE (1350 3700);
FORCEPROP 2 LAST CDS_LIB standard
J 2
(1675 3825);
DISPLAY INVISIBLE (1675 3825);
FORCEADD OFFPAGE..6
R 2
(1675 3775);
PAINT AQUA (1675 3775);
FORCEPROP 2 LAST $XR0 152 
J 0
(1889 3775);
DISPLAY 0.638298 (1889 3775);
PAINT MONO (1889 3775);
FORCEPROP 2 LAST PATH I134
J 0
(2000 3825);
DISPLAY 1.021277 (2000 3825);
DISPLAY INVISIBLE (2000 3825);
FORCEPROP 1 LAST COMMENT_BODY TRUE
J 2
(1575 3700);
DISPLAY 1.170213 (1575 3700);
PAINT GREEN (1575 3700);
DISPLAY INVISIBLE (1575 3700);
FORCEPROP 1 LAST OFFPAGE TRUE
J 2
(1350 3650);
DISPLAY 0.872340 (1350 3650);
PAINT AQUA (1350 3650);
DISPLAY INVISIBLE (1350 3650);
FORCEPROP 2 LAST CDS_LIB standard
J 2
(1675 3775);
DISPLAY INVISIBLE (1675 3775);
FORCEADD OFFPAGE..3
(4200 3925);
PAINT AQUA (4200 3925);
FORCEPROP 2 LAST $XR0 240 
J 0
(4414 3925);
DISPLAY 0.638298 (4414 3925);
PAINT MONO (4414 3925);
FORCEPROP 2 LAST PATH I135
J 0
(4425 3975);
DISPLAY 1.021277 (4425 3975);
DISPLAY INVISIBLE (4425 3975);
FORCEPROP 1 LAST COMMENT_BODY TRUE
J 0
(4150 3825);
DISPLAY 0.872340 (4150 3825);
PAINT GREEN (4150 3825);
DISPLAY INVISIBLE (4150 3825);
FORCEPROP 1 LAST OFFPAGE TRUE
J 0
(4525 3800);
DISPLAY 0.872340 (4525 3800);
PAINT AQUA (4525 3800);
DISPLAY INVISIBLE (4525 3800);
FORCEPROP 2 LAST CDS_LIB standard
J 0
(4200 3925);
DISPLAY INVISIBLE (4200 3925);
FORCEADD OFFPAGE..3
(4200 3875);
PAINT AQUA (4200 3875);
FORCEPROP 2 LAST $XR0 240 
J 0
(4414 3875);
DISPLAY 0.638298 (4414 3875);
PAINT MONO (4414 3875);
FORCEPROP 2 LAST PATH I136
J 0
(4425 3925);
DISPLAY 1.021277 (4425 3925);
DISPLAY INVISIBLE (4425 3925);
FORCEPROP 1 LAST COMMENT_BODY TRUE
J 0
(4150 3775);
DISPLAY 0.872340 (4150 3775);
PAINT GREEN (4150 3775);
DISPLAY INVISIBLE (4150 3775);
FORCEPROP 1 LAST OFFPAGE TRUE
J 0
(4525 3750);
DISPLAY 0.872340 (4525 3750);
PAINT AQUA (4525 3750);
DISPLAY INVISIBLE (4525 3750);
FORCEPROP 2 LAST CDS_LIB standard
J 0
(4200 3875);
DISPLAY INVISIBLE (4200 3875);
FORCEADD Q_RES..1
(2550 3875);
FORCEPROP 1 LAST PART_NUMBER CS00002JB13
J 0
(2275 3750);
DISPLAY 0.723404 (2275 3750);
PAINT WHITE (2275 3750);
DISPLAY INVISIBLE (2275 3750);
FORCEPROP 0 LAST ROOM USB1_BOM1
J 0
(2100 3825);
DISPLAY 0.808511 (2100 3825);
FORCEPROP 1 LAST PACK_TYPE 0402LF
J 0
(2075 3875);
DISPLAY 0.723404 (2075 3875);
FORCEPROP 1 LAST MATERIAL CHIP
J 0
(1900 3875);
DISPLAY 0.723404 (1900 3875);
FORCEPROP 1 LAST VALUE 0
J 2
(2700 3875);
DISPLAY 0.723404 (2700 3875);
FORCEPROP 1 LAST $LOCATION R3652
J 0
(2300 3875);
DISPLAY 0.723404 (2300 3875);
FORCEPROP 1 LASTPIN (2450 3875) $PN 1
J 0
(2462 3887);
DISPLAY 0.723404 (2462 3887);
PAINT MONO (2462 3887);
FORCEPROP 1 LASTPIN (2650 3875) $PN 2
J 0
(2612 3887);
DISPLAY 0.723404 (2612 3887);
PAINT MONO (2612 3887);
FORCEPROP 1 LAST PATH I137
J 0
(2500 4025);
DISPLAY 0.978723 (2500 4025);
PAINT WHITE (2500 4025);
DISPLAY INVISIBLE (2500 4025);
FORCEPROP 2 LAST CDS_LIB pure_quanta
J 0
(2550 3875);
DISPLAY INVISIBLE (2550 3875);
FORCEPROP 1 LAST WATTAGE 1/16W
J 2
(2625 3800);
DISPLAY 0.723404 (2625 3800);
PAINT SKYBLUE (2625 3800);
DISPLAY INVISIBLE (2625 3800);
FORCEPROP 1 LAST TOLERANCE 5%
J 0
(2350 3800);
DISPLAY 0.723404 (2350 3800);
PAINT SKYBLUE (2350 3800);
DISPLAY INVISIBLE (2350 3800);
FORCEPROP 2 LAST CDS_LOCATION R3652
J 0
(2500 4075);
DISPLAY 1.021277 (2500 4075);
DISPLAY INVISIBLE (2500 4075);
FORCEPROP 2 LAST $SEC 1
J 0
(2500 4075);
DISPLAY 0.680851 (2500 4075);
PAINT MONO (2500 4075);
DISPLAY INVISIBLE (2500 4075);
FORCEPROP 2 LAST CDS_SEC 1
J 0
(2500 4075);
DISPLAY 1.021277 (2500 4075);
DISPLAY INVISIBLE (2500 4075);
FORCEADD Q_RES..1
(2550 3925);
FORCEPROP 1 LAST PART_NUMBER CS00002JB13
J 0
(2275 3800);
DISPLAY 0.723404 (2275 3800);
PAINT WHITE (2275 3800);
DISPLAY INVISIBLE (2275 3800);
FORCEPROP 0 LAST ROOM USB1_BOM1
J 0
(2100 3975);
DISPLAY 0.808511 (2100 3975);
FORCEPROP 1 LAST PACK_TYPE 0402LF
J 0
(2075 3925);
DISPLAY 0.723404 (2075 3925);
FORCEPROP 1 LAST VALUE 0
J 2
(2700 3925);
DISPLAY 0.723404 (2700 3925);
FORCEPROP 1 LAST MATERIAL CHIP
J 0
(1900 3925);
DISPLAY 0.723404 (1900 3925);
FORCEPROP 1 LAST $LOCATION R3651
J 0
(2300 3925);
DISPLAY 0.723404 (2300 3925);
FORCEPROP 1 LASTPIN (2450 3925) $PN 1
J 0
(2462 3937);
DISPLAY 0.723404 (2462 3937);
PAINT MONO (2462 3937);
FORCEPROP 1 LASTPIN (2650 3925) $PN 2
J 0
(2612 3937);
DISPLAY 0.723404 (2612 3937);
PAINT MONO (2612 3937);
FORCEPROP 1 LAST PATH I138
J 0
(2500 4075);
DISPLAY 0.978723 (2500 4075);
PAINT WHITE (2500 4075);
DISPLAY INVISIBLE (2500 4075);
FORCEPROP 2 LAST CDS_LIB pure_quanta
J 0
(2550 3925);
DISPLAY INVISIBLE (2550 3925);
FORCEPROP 1 LAST TOLERANCE 5%
J 0
(2350 3850);
DISPLAY 0.723404 (2350 3850);
PAINT SKYBLUE (2350 3850);
DISPLAY INVISIBLE (2350 3850);
FORCEPROP 1 LAST WATTAGE 1/16W
J 2
(2625 3850);
DISPLAY 0.723404 (2625 3850);
PAINT SKYBLUE (2625 3850);
DISPLAY INVISIBLE (2625 3850);
FORCEPROP 2 LAST CDS_LOCATION R3651
J 0
(2500 4125);
DISPLAY 1.021277 (2500 4125);
DISPLAY INVISIBLE (2500 4125);
FORCEPROP 2 LAST $SEC 1
J 0
(2500 4125);
DISPLAY 0.680851 (2500 4125);
PAINT MONO (2500 4125);
DISPLAY INVISIBLE (2500 4125);
FORCEPROP 2 LAST CDS_SEC 1
J 0
(2500 4125);
DISPLAY 1.021277 (2500 4125);
DISPLAY INVISIBLE (2500 4125);
FORCEADD Q_RES..2
(-1075 3100);
FORCEPROP 1 LAST PART_NUMBER CS16802FB03
J 0
(-1035 2975);
DISPLAY 0.510638 (-1035 2975);
DISPLAY INVISIBLE (-1035 2975);
FORCEPROP 1 LAST PACK_TYPE 0402LF
J 0
(-1035 2925);
DISPLAY 0.510638 (-1035 2925);
FORCEPROP 1 LAST MATERIAL CHIP
J 0
(-1035 3025);
DISPLAY 0.510638 (-1035 3025);
FORCEPROP 1 LAST WATTAGE 1/16W
J 0
(-1035 3075);
DISPLAY 0.510638 (-1035 3075);
FORCEPROP 1 LAST TOLERANCE 1%
J 0
(-1030 3125);
DISPLAY 0.510638 (-1030 3125);
FORCEPROP 1 LAST VALUE 680
J 0
(-1030 3175);
DISPLAY 0.404255 (-1030 3175);
FORCEPROP 0 LAST ROOM USB1_BOM1
J 0
(-1050 2875);
DISPLAY 0.638298 (-1050 2875);
FORCEPROP 1 LAST $LOCATION R3653
J 0
(-1030 3225);
DISPLAY 0.510638 (-1030 3225);
FORCEPROP 1 LASTPIN (-1075 3200) $PN 1
J 0
(-1070 3162);
DISPLAY 0.787234 (-1070 3162);
PAINT MONO (-1070 3162);
FORCEPROP 1 LASTPIN (-1075 3000) $PN 2
J 0
(-1070 3010);
DISPLAY 0.787234 (-1070 3010);
PAINT MONO (-1070 3010);
FORCEPROP 1 LAST PATH I139
J 0
(-1025 3275);
DISPLAY 0.978723 (-1025 3275);
PAINT WHITE (-1025 3275);
DISPLAY INVISIBLE (-1025 3275);
FORCEPROP 2 LAST CDS_LIB pure_quanta
J 0
(-1075 3100);
DISPLAY INVISIBLE (-1075 3100);
FORCEPROP 0 LAST CDS_LOCATION R3653
J 0
(-1025 3275);
DISPLAY 1.021277 (-1025 3275);
DISPLAY INVISIBLE (-1025 3275);
FORCEPROP 0 LAST $SEC 1
J 0
(-1025 3275);
DISPLAY 0.680851 (-1025 3275);
PAINT MONO (-1025 3275);
DISPLAY INVISIBLE (-1025 3275);
FORCEPROP 0 LAST CDS_SEC 1
J 0
(-1025 3275);
DISPLAY 1.021277 (-1025 3275);
DISPLAY INVISIBLE (-1025 3275);
FORCEADD UNIVERSAL_GND..1
(-1075 2825);
FORCEPROP 3 LASTPIN (-1075 2875) SIG_NAME GND\g
J 0
(-1065 2885);
DISPLAY 0.659574 (-1065 2885);
PAINT MONO (-1065 2885);
DISPLAY INVISIBLE (-1065 2885);
FORCEPROP 1 LAST PATH I140
J 0
(-1000 2825);
DISPLAY 0.872340 (-1000 2825);
PAINT AQUA (-1000 2825);
DISPLAY INVISIBLE (-1000 2825);
FORCEPROP 1 LAST HDL_POWER GND
J 1
(-1050 2750);
DISPLAY 0.872340 (-1050 2750);
PAINT GREEN (-1050 2750);
DISPLAY INVISIBLE (-1050 2750);
FORCEPROP 2 LAST CDS_LIB logical_power
J 0
(-1075 2825);
DISPLAY INVISIBLE (-1075 2825);
FORCEADD Q_CAP..1
R 2
(-1175 4500);
FORCEPROP 1 LAST PART_NUMBER CH4104K1B00
J 0
(-1100 4350);
DISPLAY 0.510638 (-1100 4350);
DISPLAY INVISIBLE (-1100 4350);
FORCEPROP 0 LAST ROOM USB1_BOM1
J 0
(-1100 4675);
DISPLAY 0.510638 (-1100 4675);
FORCEPROP 1 LAST PACK_TYPE 0402
J 0
(-1100 4300);
DISPLAY 0.510638 (-1100 4300);
FORCEPROP 1 LAST MATERIAL X7R
J 0
(-1100 4400);
DISPLAY 0.510638 (-1100 4400);
FORCEPROP 1 LAST TOLERANCE 10%
J 0
(-1100 4450);
DISPLAY 0.510638 (-1100 4450);
FORCEPROP 1 LAST VOLTAGE 25V
J 0
(-1100 4500);
DISPLAY 0.510638 (-1100 4500);
FORCEPROP 1 LAST VALUE 0.1UF
J 0
(-1100 4550);
DISPLAY 0.510638 (-1100 4550);
FORCEPROP 1 LAST $LOCATION C2034
J 0
(-1100 4600);
DISPLAY 0.638298 (-1100 4600);
FORCEPROP 1 LASTPIN (-1175 4600) $PN 1
J 2
(-1185 4580);
DISPLAY 0.787234 (-1185 4580);
PAINT MONO (-1185 4580);
FORCEPROP 1 LASTPIN (-1175 4400) $PN 2
J 2
(-1185 4380);
DISPLAY 0.787234 (-1185 4380);
PAINT MONO (-1185 4380);
FORCEPROP 1 LAST PATH I142
J 2
(-1225 4650);
DISPLAY 0.978723 (-1225 4650);
PAINT WHITE (-1225 4650);
DISPLAY INVISIBLE (-1225 4650);
FORCEPROP 2 LAST CDS_LIB pure_quanta
J 0
(-1175 4500);
DISPLAY INVISIBLE (-1175 4500);
FORCEPROP 0 LAST CDS_LOCATION C2034
J 0
(-1225 4650);
DISPLAY 1.021277 (-1225 4650);
DISPLAY INVISIBLE (-1225 4650);
FORCEPROP 0 LAST $SEC 1
J 0
(-1225 4650);
DISPLAY 0.680851 (-1225 4650);
PAINT MONO (-1225 4650);
DISPLAY INVISIBLE (-1225 4650);
FORCEPROP 0 LAST CDS_SEC 1
J 0
(-1225 4650);
DISPLAY 1.021277 (-1225 4650);
DISPLAY INVISIBLE (-1225 4650);
FORCEADD Q_CAP..1
R 2
(-1550 4500);
FORCEPROP 1 LAST PART_NUMBER CH4104K1B00
J 0
(-1475 4350);
DISPLAY 0.510638 (-1475 4350);
DISPLAY INVISIBLE (-1475 4350);
FORCEPROP 1 LAST PACK_TYPE 0402
J 0
(-1475 4300);
DISPLAY 0.510638 (-1475 4300);
FORCEPROP 1 LAST MATERIAL X7R
J 0
(-1475 4400);
DISPLAY 0.510638 (-1475 4400);
FORCEPROP 1 LAST TOLERANCE 10%
J 0
(-1475 4450);
DISPLAY 0.510638 (-1475 4450);
FORCEPROP 1 LAST VOLTAGE 25V
J 0
(-1475 4500);
DISPLAY 0.510638 (-1475 4500);
FORCEPROP 1 LAST VALUE 0.1UF
J 0
(-1475 4550);
DISPLAY 0.510638 (-1475 4550);
FORCEPROP 0 LAST ROOM USB1_BOM1
J 0
(-1475 4650);
DISPLAY 0.510638 (-1475 4650);
FORCEPROP 1 LAST $LOCATION C2033
J 0
(-1475 4600);
DISPLAY 0.510638 (-1475 4600);
FORCEPROP 1 LASTPIN (-1550 4600) $PN 1
J 2
(-1560 4580);
DISPLAY 0.787234 (-1560 4580);
PAINT MONO (-1560 4580);
FORCEPROP 1 LASTPIN (-1550 4400) $PN 2
J 2
(-1560 4380);
DISPLAY 0.787234 (-1560 4380);
PAINT MONO (-1560 4380);
FORCEPROP 1 LAST PATH I143
J 2
(-1600 4650);
DISPLAY 0.978723 (-1600 4650);
PAINT WHITE (-1600 4650);
DISPLAY INVISIBLE (-1600 4650);
FORCEPROP 2 LAST CDS_LIB pure_quanta
J 0
(-1550 4500);
DISPLAY INVISIBLE (-1550 4500);
FORCEPROP 0 LAST CDS_LOCATION C2033
J 0
(-1600 4650);
DISPLAY 1.021277 (-1600 4650);
DISPLAY INVISIBLE (-1600 4650);
FORCEPROP 0 LAST $SEC 1
J 0
(-1600 4650);
DISPLAY 0.680851 (-1600 4650);
PAINT MONO (-1600 4650);
DISPLAY INVISIBLE (-1600 4650);
FORCEPROP 0 LAST CDS_SEC 1
J 0
(-1600 4650);
DISPLAY 1.021277 (-1600 4650);
DISPLAY INVISIBLE (-1600 4650);
FORCEADD UNIVERSAL_POWER..1
R 2
(-4000 4950);
FORCEPROP 3 LASTPIN (-4000 4900) SIG_NAME P3V3_AUX\g
J 0
(-3990 4910);
DISPLAY 0.659574 (-3990 4910);
PAINT MONO (-3990 4910);
DISPLAY INVISIBLE (-3990 4910);
FORCEPROP 1 LAST HDL_POWER P3V3_AUX
J 1
(-4000 5000);
DISPLAY 0.723404 (-4000 5000);
PAINT GREEN (-4000 5000);
FORCEPROP 1 LAST PATH I144
J 2
(-4050 4975);
DISPLAY 0.872340 (-4050 4975);
PAINT AQUA (-4050 4975);
DISPLAY INVISIBLE (-4050 4975);
FORCEPROP 2 LAST CDS_LIB logical_power
J 0
(-4000 4950);
DISPLAY INVISIBLE (-4000 4950);
FORCEADD Q_CAP..1
R 2
(-1925 4500);
FORCEPROP 1 LAST PART_NUMBER CH4104K1B00
J 0
(-1850 4350);
DISPLAY 0.510638 (-1850 4350);
DISPLAY INVISIBLE (-1850 4350);
FORCEPROP 1 LAST VALUE 0.1UF
J 0
(-1850 4550);
DISPLAY 0.510638 (-1850 4550);
FORCEPROP 0 LAST ROOM USB1_BOM1
J 0
(-1850 4650);
DISPLAY 0.510638 (-1850 4650);
FORCEPROP 1 LAST PACK_TYPE 0402
J 0
(-1850 4300);
DISPLAY 0.510638 (-1850 4300);
FORCEPROP 1 LAST MATERIAL X7R
J 0
(-1850 4400);
DISPLAY 0.510638 (-1850 4400);
FORCEPROP 1 LAST VOLTAGE 25V
J 0
(-1850 4500);
DISPLAY 0.510638 (-1850 4500);
FORCEPROP 1 LAST TOLERANCE 10%
J 0
(-1850 4450);
DISPLAY 0.510638 (-1850 4450);
FORCEPROP 1 LAST $LOCATION C2032
J 0
(-1850 4600);
DISPLAY 0.510638 (-1850 4600);
FORCEPROP 1 LASTPIN (-1925 4600) $PN 1
J 2
(-1935 4580);
DISPLAY 0.787234 (-1935 4580);
PAINT MONO (-1935 4580);
FORCEPROP 1 LASTPIN (-1925 4400) $PN 2
J 2
(-1935 4380);
DISPLAY 0.787234 (-1935 4380);
PAINT MONO (-1935 4380);
FORCEPROP 1 LAST PATH I145
J 2
(-1975 4650);
DISPLAY 0.978723 (-1975 4650);
PAINT WHITE (-1975 4650);
DISPLAY INVISIBLE (-1975 4650);
FORCEPROP 2 LAST CDS_LIB pure_quanta
J 0
(-1925 4500);
DISPLAY INVISIBLE (-1925 4500);
FORCEPROP 0 LAST CDS_LOCATION C2032
J 0
(-1975 4650);
DISPLAY 1.021277 (-1975 4650);
DISPLAY INVISIBLE (-1975 4650);
FORCEPROP 0 LAST $SEC 1
J 0
(-1975 4650);
DISPLAY 0.680851 (-1975 4650);
PAINT MONO (-1975 4650);
DISPLAY INVISIBLE (-1975 4650);
FORCEPROP 0 LAST CDS_SEC 1
J 0
(-1975 4650);
DISPLAY 1.021277 (-1975 4650);
DISPLAY INVISIBLE (-1975 4650);
FORCEADD Q_CAP..1
(-825 4500);
FORCEPROP 1 LAST PART_NUMBER CH5104KEB02
J 0
(-775 4375);
DISPLAY 0.468085 (-775 4375);
DISPLAY INVISIBLE (-775 4375);
FORCEPROP 1 LAST PACK_TYPE C0402
J 0
(-775 4325);
DISPLAY 0.468085 (-775 4325);
FORCEPROP 1 LAST MATERIAL X6S
J 0
(-775 4425);
DISPLAY 0.468085 (-775 4425);
FORCEPROP 1 LAST TOLERANCE 10%
J 0
(-775 4475);
DISPLAY 0.468085 (-775 4475);
FORCEPROP 1 LAST VOLTAGE 25V
J 0
(-775 4525);
DISPLAY 0.468085 (-775 4525);
FORCEPROP 1 LAST VALUE 1UF
J 0
(-775 4575);
DISPLAY 0.468085 (-775 4575);
FORCEPROP 0 LAST ROOM USB1_BOM1
J 0
(-775 4700);
DISPLAY 0.510638 (-775 4700);
FORCEPROP 1 LAST $LOCATION C2035
J 0
(-775 4625);
DISPLAY 0.638298 (-775 4625);
FORCEPROP 1 LASTPIN (-825 4600) $PN 1
J 0
(-815 4580);
DISPLAY 0.787234 (-815 4580);
PAINT MONO (-815 4580);
FORCEPROP 1 LASTPIN (-825 4400) $PN 2
J 0
(-815 4380);
DISPLAY 0.787234 (-815 4380);
PAINT MONO (-815 4380);
FORCEPROP 1 LAST PATH I147
J 0
(-775 4650);
DISPLAY 0.978723 (-775 4650);
PAINT WHITE (-775 4650);
DISPLAY INVISIBLE (-775 4650);
FORCEPROP 2 LAST CDS_LIB pure_quanta
J 0
(-825 4500);
DISPLAY INVISIBLE (-825 4500);
FORCEPROP 0 LAST CDS_LOCATION C2035
J 0
(-775 4650);
DISPLAY 1.021277 (-775 4650);
DISPLAY INVISIBLE (-775 4650);
FORCEPROP 0 LAST $SEC 1
J 0
(-775 4650);
DISPLAY 0.680851 (-775 4650);
PAINT MONO (-775 4650);
DISPLAY INVISIBLE (-775 4650);
FORCEPROP 0 LAST CDS_SEC 1
J 0
(-775 4650);
DISPLAY 1.021277 (-775 4650);
DISPLAY INVISIBLE (-775 4650);
FORCEADD Q_CAP..1
(-2300 4500);
FORCEPROP 1 LAST PART_NUMBER CH5104KEB02
J 0
(-2250 4375);
DISPLAY 0.574468 (-2250 4375);
DISPLAY INVISIBLE (-2250 4375);
FORCEPROP 1 LAST PACK_TYPE C0402
J 0
(-2250 4325);
DISPLAY 0.574468 (-2250 4325);
FORCEPROP 1 LAST MATERIAL X6S
J 0
(-2250 4425);
DISPLAY 0.574468 (-2250 4425);
FORCEPROP 1 LAST TOLERANCE 10%
J 0
(-2250 4475);
DISPLAY 0.574468 (-2250 4475);
FORCEPROP 1 LAST VOLTAGE 25V
J 0
(-2250 4525);
DISPLAY 0.574468 (-2250 4525);
FORCEPROP 1 LAST VALUE 1UF
J 0
(-2250 4575);
DISPLAY 0.574468 (-2250 4575);
FORCEPROP 0 LAST ROOM USB1_BOM1
J 0
(-2250 4675);
DISPLAY 0.510638 (-2250 4675);
FORCEPROP 1 LAST $LOCATION C2031
J 0
(-2250 4625);
DISPLAY 0.510638 (-2250 4625);
FORCEPROP 1 LASTPIN (-2300 4600) $PN 1
J 0
(-2290 4580);
DISPLAY 0.787234 (-2290 4580);
PAINT MONO (-2290 4580);
FORCEPROP 1 LASTPIN (-2300 4400) $PN 2
J 0
(-2290 4380);
DISPLAY 0.787234 (-2290 4380);
PAINT MONO (-2290 4380);
FORCEPROP 1 LAST PATH I148
J 0
(-2250 4650);
DISPLAY 0.978723 (-2250 4650);
PAINT WHITE (-2250 4650);
DISPLAY INVISIBLE (-2250 4650);
FORCEPROP 2 LAST CDS_LIB pure_quanta
J 0
(-2300 4500);
DISPLAY INVISIBLE (-2300 4500);
FORCEPROP 0 LAST CDS_LOCATION C2031
J 0
(-2250 4650);
DISPLAY 1.021277 (-2250 4650);
DISPLAY INVISIBLE (-2250 4650);
FORCEPROP 0 LAST $SEC 1
J 0
(-2250 4650);
DISPLAY 0.680851 (-2250 4650);
PAINT MONO (-2250 4650);
DISPLAY INVISIBLE (-2250 4650);
FORCEPROP 0 LAST CDS_SEC 1
J 0
(-2250 4650);
DISPLAY 1.021277 (-2250 4650);
DISPLAY INVISIBLE (-2250 4650);
FORCEADD UNIVERSAL_POWER..1
R 2
(-1900 4075);
FORCEPROP 3 LASTPIN (-1900 4025) SIG_NAME P3V3_AUX\g
J 0
(-1890 4035);
DISPLAY 0.659574 (-1890 4035);
PAINT MONO (-1890 4035);
DISPLAY INVISIBLE (-1890 4035);
FORCEPROP 1 LAST HDL_POWER P3V3_AUX
J 1
(-1900 4125);
DISPLAY 0.723404 (-1900 4125);
PAINT GREEN (-1900 4125);
FORCEPROP 1 LAST PATH I151
J 2
(-1950 4100);
DISPLAY 0.872340 (-1950 4100);
PAINT AQUA (-1950 4100);
DISPLAY INVISIBLE (-1950 4100);
FORCEPROP 2 LAST CDS_LIB logical_power
J 0
(-1900 4075);
DISPLAY INVISIBLE (-1900 4075);
FORCEADD Q_RES..1
(-2725 3425);
FORCEPROP 1 LAST PART_NUMBER CS03322FB03
J 0
(-2475 3375);
DISPLAY 0.723404 (-2475 3375);
DISPLAY INVISIBLE (-2475 3375);
FORCEPROP 0 LAST ROOM USB1_BOM1
J 0
(-2975 3325);
DISPLAY 0.638298 (-2975 3325);
FORCEPROP 1 LAST PACK_TYPE 0402LF
J 0
(-2875 3375);
DISPLAY 0.723404 (-2875 3375);
FORCEPROP 1 LAST WATTAGE 1/16W
J 2
(-3000 3375);
DISPLAY 0.723404 (-3000 3375);
FORCEPROP 1 LAST MATERIAL CHIP
J 0
(-2650 3375);
DISPLAY 0.723404 (-2650 3375);
FORCEPROP 1 LAST TOLERANCE 1%
J 0
(-2975 3375);
DISPLAY 0.723404 (-2975 3375);
FORCEPROP 1 LAST VALUE 33.2
J 2
(-2525 3425);
DISPLAY 0.723404 (-2525 3425);
FORCEPROP 1 LAST $LOCATION R3654
J 0
(-2975 3425);
DISPLAY 0.723404 (-2975 3425);
FORCEPROP 1 LAST PATH I155
J 0
(-2775 3575);
DISPLAY 0.978723 (-2775 3575);
PAINT WHITE (-2775 3575);
DISPLAY INVISIBLE (-2775 3575);
FORCEPROP 2 LAST CDS_LIB pure_quanta
J 0
(-2725 3425);
DISPLAY INVISIBLE (-2725 3425);
FORCEPROP 2 LAST CDS_LOCATION R3654
J 0
(-2775 3625);
DISPLAY 1.021277 (-2775 3625);
DISPLAY INVISIBLE (-2775 3625);
FORCEPROP 0 LAST $SEC 1
J 0
(-3025 3500);
DISPLAY INVISIBLE (-3025 3500);
FORCEPROP 0 LAST CDS_SEC 1
J 0
(-3025 3500);
DISPLAY INVISIBLE (-3025 3500);
FORCEPROP 1 LASTPIN (-2825 3425) $PN 1
J 0
(-2813 3437);
DISPLAY 0.787234 (-2813 3437);
PAINT MONO (-2813 3437);
DISPLAY INVISIBLE (-2813 3437);
FORCEPROP 1 LASTPIN (-2625 3425) $PN 2
J 0
(-2663 3437);
DISPLAY 0.787234 (-2663 3437);
PAINT MONO (-2663 3437);
DISPLAY INVISIBLE (-2663 3437);
FORCEADD OFFPAGE..1
(-3525 3425);
PAINT AQUA (-3525 3425);
FORCEPROP 2 LAST $XR1 196 
J 0
(-3897 3425);
DISPLAY 0.638298 (-3897 3425);
PAINT MONO (-3897 3425);
FORCEPROP 2 LAST $XR0 227 
J 0
(-3777 3425);
DISPLAY 0.638298 (-3777 3425);
PAINT MONO (-3777 3425);
FORCEPROP 2 LAST PATH I156
J 0
(-3700 3475);
DISPLAY 1.021277 (-3700 3475);
DISPLAY INVISIBLE (-3700 3475);
FORCEPROP 1 LAST COMMENT_BODY TRUE
J 0
(-3400 3325);
DISPLAY 0.872340 (-3400 3325);
PAINT GREEN (-3400 3325);
DISPLAY INVISIBLE (-3400 3325);
FORCEPROP 1 LAST OFFPAGE TRUE
J 0
(-3200 3300);
DISPLAY 0.872340 (-3200 3300);
PAINT AQUA (-3200 3300);
DISPLAY INVISIBLE (-3200 3300);
FORCEPROP 2 LAST CDS_LIB standard
J 0
(-3525 3425);
DISPLAY INVISIBLE (-3525 3425);
FORCEADD UNIVERSAL_GND..1
(-2275 2850);
FORCEPROP 3 LASTPIN (-2275 2900) SIG_NAME GND\g
J 0
(-2265 2910);
DISPLAY 0.659574 (-2265 2910);
PAINT MONO (-2265 2910);
DISPLAY INVISIBLE (-2265 2910);
FORCEPROP 1 LAST PATH I157
J 0
(-2200 2850);
DISPLAY 0.872340 (-2200 2850);
PAINT AQUA (-2200 2850);
DISPLAY INVISIBLE (-2200 2850);
FORCEPROP 1 LAST HDL_POWER GND
J 1
(-2250 2775);
DISPLAY 0.872340 (-2250 2775);
PAINT GREEN (-2250 2775);
DISPLAY INVISIBLE (-2250 2775);
FORCEPROP 2 LAST CDS_LIB logical_power
J 0
(-2275 2850);
DISPLAY INVISIBLE (-2275 2850);
FORCEADD Q_CAP..1
(-2275 3150);
FORCEPROP 1 LAST PART_NUMBER CH5104KEB02
J 0
(-2225 3000);
DISPLAY 0.574468 (-2225 3000);
DISPLAY INVISIBLE (-2225 3000);
FORCEPROP 0 LAST ROOM USB1_BOM1
J 0
(-2250 3300);
DISPLAY 0.808511 (-2250 3300);
FORCEPROP 1 LAST VALUE 1UF
J 0
(-2225 3200);
DISPLAY 0.574468 (-2225 3200);
FORCEPROP 1 LAST TOLERANCE 10%
J 0
(-2225 3100);
DISPLAY 0.574468 (-2225 3100);
FORCEPROP 1 LAST MATERIAL X6S
J 0
(-2225 3050);
DISPLAY 0.574468 (-2225 3050);
FORCEPROP 1 LAST PACK_TYPE C0402
J 0
(-2225 2950);
DISPLAY 0.574468 (-2225 2950);
FORCEPROP 1 LAST VOLTAGE 25V
J 0
(-2225 3150);
DISPLAY 0.574468 (-2225 3150);
FORCEPROP 1 LAST $LOCATION C2041
J 0
(-2225 3250);
DISPLAY 0.978723 (-2225 3250);
FORCEPROP 1 LASTPIN (-2275 3250) $PN 1
J 0
(-2265 3230);
DISPLAY 0.787234 (-2265 3230);
PAINT MONO (-2265 3230);
FORCEPROP 1 LASTPIN (-2275 3050) $PN 2
J 0
(-2265 3030);
DISPLAY 0.787234 (-2265 3030);
PAINT MONO (-2265 3030);
FORCEPROP 1 LAST PATH I158
J 0
(-2225 3300);
DISPLAY 0.978723 (-2225 3300);
PAINT WHITE (-2225 3300);
DISPLAY INVISIBLE (-2225 3300);
FORCEPROP 2 LAST CDS_LIB pure_quanta
J 0
(-2275 3150);
DISPLAY INVISIBLE (-2275 3150);
FORCEPROP 0 LAST CDS_LOCATION C2041
J 0
(-2225 3300);
DISPLAY 1.021277 (-2225 3300);
DISPLAY INVISIBLE (-2225 3300);
FORCEPROP 0 LAST $SEC 1
J 0
(-2225 3300);
DISPLAY 0.680851 (-2225 3300);
PAINT MONO (-2225 3300);
DISPLAY INVISIBLE (-2225 3300);
FORCEPROP 0 LAST CDS_SEC 1
J 0
(-2225 3300);
DISPLAY 1.021277 (-2225 3300);
DISPLAY INVISIBLE (-2225 3300);
FORCEADD Q_RES..2
(-1900 3775);
FORCEPROP 1 LAST PART_NUMBER CS31002FB08
J 0
(-1860 3650);
DISPLAY 0.638298 (-1860 3650);
DISPLAY INVISIBLE (-1860 3650);
FORCEPROP 0 LAST ROOM USB1_BOM1
J 0
(-1850 3950);
DISPLAY 0.638298 (-1850 3950);
FORCEPROP 1 LAST WATTAGE 1/16W
J 0
(-1860 3750);
DISPLAY 0.638298 (-1860 3750);
FORCEPROP 1 LAST MATERIAL CHIP
J 0
(-1860 3700);
DISPLAY 0.638298 (-1860 3700);
FORCEPROP 1 LAST TOLERANCE 1%
J 0
(-1855 3800);
DISPLAY 0.638298 (-1855 3800);
FORCEPROP 1 LAST VALUE 10K
J 0
(-1855 3850);
DISPLAY 0.638298 (-1855 3850);
FORCEPROP 1 LAST PACK_TYPE 0402LF
J 0
(-1860 3600);
DISPLAY 0.638298 (-1860 3600);
FORCEPROP 1 LAST $LOCATION R3660
J 0
(-1855 3900);
DISPLAY 0.638298 (-1855 3900);
FORCEPROP 1 LASTPIN (-1900 3875) $PN 1
J 0
(-1895 3837);
DISPLAY 0.787234 (-1895 3837);
PAINT MONO (-1895 3837);
FORCEPROP 1 LASTPIN (-1900 3675) $PN 2
J 0
(-1895 3685);
DISPLAY 0.787234 (-1895 3685);
PAINT MONO (-1895 3685);
FORCEPROP 1 LAST PATH I159
J 0
(-1850 3950);
DISPLAY 0.978723 (-1850 3950);
PAINT WHITE (-1850 3950);
DISPLAY INVISIBLE (-1850 3950);
FORCEPROP 2 LAST CDS_LIB pure_quanta
J 0
(-1900 3775);
DISPLAY INVISIBLE (-1900 3775);
FORCEPROP 0 LAST CDS_LOCATION R3660
J 0
(-1850 3950);
DISPLAY 1.021277 (-1850 3950);
DISPLAY INVISIBLE (-1850 3950);
FORCEPROP 0 LAST $SEC 1
J 0
(-1850 3950);
DISPLAY 0.680851 (-1850 3950);
PAINT MONO (-1850 3950);
DISPLAY INVISIBLE (-1850 3950);
FORCEPROP 0 LAST CDS_SEC 1
J 0
(-1850 3950);
DISPLAY 1.021277 (-1850 3950);
DISPLAY INVISIBLE (-1850 3950);
FORCEADD Q_RES..1
(-3750 4800);
FORCEPROP 1 LAST PART_NUMBER CS00002JB13
J 0
(-4025 4675);
DISPLAY 0.723404 (-4025 4675);
PAINT WHITE (-4025 4675);
DISPLAY INVISIBLE (-4025 4675);
FORCEPROP 0 LAST ROOM USB1_BOM1
J 0
(-3875 4675);
DISPLAY 0.638298 (-3875 4675);
FORCEPROP 1 LAST MATERIAL CHIP
J 0
(-3900 4725);
DISPLAY 0.723404 (-3900 4725);
FORCEPROP 1 LAST PACK_TYPE 0402LF
J 0
(-3750 4725);
DISPLAY 0.723404 (-3750 4725);
FORCEPROP 1 LAST VALUE 0
J 2
(-3600 4800);
DISPLAY 0.723404 (-3600 4800);
FORCEPROP 1 LAST $LOCATION R3655
J 0
(-3975 4800);
DISPLAY 0.638298 (-3975 4800);
FORCEPROP 1 LASTPIN (-3850 4800) $PN 1
J 0
(-3838 4812);
DISPLAY 0.787234 (-3838 4812);
PAINT MONO (-3838 4812);
FORCEPROP 1 LASTPIN (-3650 4800) $PN 2
J 0
(-3688 4812);
DISPLAY 0.787234 (-3688 4812);
PAINT MONO (-3688 4812);
FORCEPROP 1 LAST PATH I161
J 0
(-3800 4950);
DISPLAY 0.978723 (-3800 4950);
PAINT WHITE (-3800 4950);
DISPLAY INVISIBLE (-3800 4950);
FORCEPROP 1 LAST TOLERANCE 5%
J 0
(-3950 4725);
DISPLAY 0.723404 (-3950 4725);
PAINT SKYBLUE (-3950 4725);
DISPLAY INVISIBLE (-3950 4725);
FORCEPROP 1 LAST WATTAGE 1/16W
J 2
(-3675 4725);
DISPLAY 0.723404 (-3675 4725);
PAINT SKYBLUE (-3675 4725);
DISPLAY INVISIBLE (-3675 4725);
FORCEPROP 2 LAST CDS_LIB pure_quanta
J 0
(-3750 4800);
DISPLAY INVISIBLE (-3750 4800);
FORCEPROP 0 LAST CDS_LOCATION R3655
J 0
(-3600 4850);
DISPLAY 1.021277 (-3600 4850);
DISPLAY INVISIBLE (-3600 4850);
FORCEPROP 0 LAST $SEC 1
J 0
(-3600 4850);
DISPLAY 0.680851 (-3600 4850);
PAINT MONO (-3600 4850);
DISPLAY INVISIBLE (-3600 4850);
FORCEPROP 0 LAST CDS_SEC 1
J 0
(-3600 4850);
DISPLAY 1.021277 (-3600 4850);
DISPLAY INVISIBLE (-3600 4850);
FORCEADD Q_CAP..1
R 2
(-2675 4500);
FORCEPROP 1 LAST PART_NUMBER CH4104K1B00
J 0
(-2600 4375);
DISPLAY 0.510638 (-2600 4375);
DISPLAY INVISIBLE (-2600 4375);
FORCEPROP 1 LAST VALUE 0.1UF
J 0
(-2600 4575);
DISPLAY 0.510638 (-2600 4575);
FORCEPROP 1 LAST PACK_TYPE 0402
J 0
(-2600 4325);
DISPLAY 0.510638 (-2600 4325);
FORCEPROP 1 LAST MATERIAL X7R
J 0
(-2600 4425);
DISPLAY 0.510638 (-2600 4425);
FORCEPROP 1 LAST TOLERANCE 10%
J 0
(-2600 4475);
DISPLAY 0.510638 (-2600 4475);
FORCEPROP 1 LAST VOLTAGE 25V
J 0
(-2600 4525);
DISPLAY 0.510638 (-2600 4525);
FORCEPROP 0 LAST ROOM USB1_BOM1
J 0
(-2600 4675);
DISPLAY 0.510638 (-2600 4675);
FORCEPROP 1 LAST $LOCATION C2040
J 0
(-2600 4625);
DISPLAY 0.638298 (-2600 4625);
FORCEPROP 1 LASTPIN (-2675 4600) $PN 1
J 2
(-2685 4580);
DISPLAY 0.787234 (-2685 4580);
PAINT MONO (-2685 4580);
FORCEPROP 1 LASTPIN (-2675 4400) $PN 2
J 2
(-2685 4380);
DISPLAY 0.787234 (-2685 4380);
PAINT MONO (-2685 4380);
FORCEPROP 1 LAST PATH I162
J 2
(-2725 4650);
DISPLAY 0.978723 (-2725 4650);
PAINT WHITE (-2725 4650);
DISPLAY INVISIBLE (-2725 4650);
FORCEPROP 2 LAST CDS_LIB pure_quanta
J 0
(-2675 4500);
DISPLAY INVISIBLE (-2675 4500);
FORCEPROP 0 LAST CDS_LOCATION C2040
J 0
(-2575 4625);
DISPLAY 1.021277 (-2575 4625);
DISPLAY INVISIBLE (-2575 4625);
FORCEPROP 0 LAST $SEC 1
J 0
(-2575 4625);
DISPLAY 0.680851 (-2575 4625);
PAINT MONO (-2575 4625);
DISPLAY INVISIBLE (-2575 4625);
FORCEPROP 0 LAST CDS_SEC 1
J 0
(-2575 4625);
DISPLAY 1.021277 (-2575 4625);
DISPLAY INVISIBLE (-2575 4625);
FORCEADD Q_CAP..1
R 2
(-3075 4500);
FORCEPROP 1 LAST PART_NUMBER CH4104K1B00
J 0
(-3000 4350);
DISPLAY 0.510638 (-3000 4350);
DISPLAY INVISIBLE (-3000 4350);
FORCEPROP 1 LAST VALUE 0.1UF
J 0
(-3000 4550);
DISPLAY 0.510638 (-3000 4550);
FORCEPROP 1 LAST TOLERANCE 10%
J 0
(-3000 4450);
DISPLAY 0.510638 (-3000 4450);
FORCEPROP 0 LAST ROOM USB1_BOM1
J 0
(-3000 4675);
DISPLAY 0.510638 (-3000 4675);
FORCEPROP 1 LAST PACK_TYPE 0402
J 0
(-3000 4300);
DISPLAY 0.510638 (-3000 4300);
FORCEPROP 1 LAST MATERIAL X7R
J 0
(-3000 4400);
DISPLAY 0.510638 (-3000 4400);
FORCEPROP 1 LAST VOLTAGE 25V
J 0
(-3000 4500);
DISPLAY 0.510638 (-3000 4500);
FORCEPROP 1 LAST $LOCATION C2039
J 0
(-3000 4600);
DISPLAY 0.638298 (-3000 4600);
FORCEPROP 1 LASTPIN (-3075 4600) $PN 1
J 2
(-3085 4580);
DISPLAY 0.787234 (-3085 4580);
PAINT MONO (-3085 4580);
FORCEPROP 1 LASTPIN (-3075 4400) $PN 2
J 2
(-3085 4380);
DISPLAY 0.787234 (-3085 4380);
PAINT MONO (-3085 4380);
FORCEPROP 1 LAST PATH I163
J 2
(-3125 4650);
DISPLAY 0.978723 (-3125 4650);
PAINT WHITE (-3125 4650);
DISPLAY INVISIBLE (-3125 4650);
FORCEPROP 2 LAST CDS_LIB pure_quanta
J 0
(-3075 4500);
DISPLAY INVISIBLE (-3075 4500);
FORCEPROP 0 LAST CDS_LOCATION C2039
J 0
(-2975 4625);
DISPLAY 1.021277 (-2975 4625);
DISPLAY INVISIBLE (-2975 4625);
FORCEPROP 0 LAST $SEC 1
J 0
(-2975 4625);
DISPLAY 0.680851 (-2975 4625);
PAINT MONO (-2975 4625);
DISPLAY INVISIBLE (-2975 4625);
FORCEPROP 0 LAST CDS_SEC 1
J 0
(-2975 4625);
DISPLAY 1.021277 (-2975 4625);
DISPLAY INVISIBLE (-2975 4625);
FORCEADD Q_CAP..1
(-3450 4500);
FORCEPROP 1 LAST PART_NUMBER CH6101MEB01
J 0
(-3400 4350);
DISPLAY 0.510638 (-3400 4350);
DISPLAY INVISIBLE (-3400 4350);
FORCEPROP 1 LAST PACK_TYPE C0402
J 0
(-3400 4300);
DISPLAY 0.510638 (-3400 4300);
FORCEPROP 1 LAST MATERIAL X6S
J 0
(-3400 4400);
DISPLAY 0.510638 (-3400 4400);
FORCEPROP 1 LAST TOLERANCE 20%
J 0
(-3400 4450);
DISPLAY 0.510638 (-3400 4450);
FORCEPROP 1 LAST VOLTAGE 6.3V
J 0
(-3400 4500);
DISPLAY 0.510638 (-3400 4500);
FORCEPROP 1 LAST VALUE 10UF
J 0
(-3400 4550);
DISPLAY 0.510638 (-3400 4550);
FORCEPROP 0 LAST ROOM USB1_BOM1
J 0
(-3400 4650);
DISPLAY 0.510638 (-3400 4650);
FORCEPROP 1 LAST $LOCATION C2038
J 0
(-3400 4600);
DISPLAY 0.510638 (-3400 4600);
FORCEPROP 1 LASTPIN (-3450 4600) $PN 1
J 0
(-3440 4580);
DISPLAY 0.787234 (-3440 4580);
PAINT MONO (-3440 4580);
FORCEPROP 1 LASTPIN (-3450 4400) $PN 2
J 0
(-3440 4380);
DISPLAY 0.787234 (-3440 4380);
PAINT MONO (-3440 4380);
FORCEPROP 1 LAST PATH I164
J 0
(-3400 4650);
DISPLAY 0.978723 (-3400 4650);
PAINT WHITE (-3400 4650);
DISPLAY INVISIBLE (-3400 4650);
FORCEPROP 2 LAST CDS_LIB pure_quanta
J 0
(-3450 4500);
DISPLAY INVISIBLE (-3450 4500);
FORCEPROP 0 LAST CDS_LOCATION C2038
J 0
(-3400 4625);
DISPLAY 1.021277 (-3400 4625);
DISPLAY INVISIBLE (-3400 4625);
FORCEPROP 0 LAST $SEC 1
J 0
(-3400 4625);
DISPLAY 0.680851 (-3400 4625);
PAINT MONO (-3400 4625);
DISPLAY INVISIBLE (-3400 4625);
FORCEPROP 0 LAST CDS_SEC 1
J 0
(-3400 4625);
DISPLAY 1.021277 (-3400 4625);
DISPLAY INVISIBLE (-3400 4625);
FORCEADD UNIVERSAL_GND..1
(-3450 4100);
FORCEPROP 3 LASTPIN (-3450 4150) SIG_NAME GND\g
J 0
(-3440 4160);
DISPLAY 0.659574 (-3440 4160);
PAINT MONO (-3440 4160);
DISPLAY INVISIBLE (-3440 4160);
FORCEPROP 1 LAST PATH I165
J 0
(-3375 4100);
DISPLAY 0.872340 (-3375 4100);
PAINT AQUA (-3375 4100);
DISPLAY INVISIBLE (-3375 4100);
FORCEPROP 1 LAST HDL_POWER GND
J 1
(-3425 4025);
DISPLAY 0.872340 (-3425 4025);
PAINT GREEN (-3425 4025);
DISPLAY INVISIBLE (-3425 4025);
FORCEPROP 2 LAST CDS_LIB logical_power
J 0
(-3450 4100);
DISPLAY INVISIBLE (-3450 4100);
FORCEADD UNIVERSAL_GND..1
(725 3125);
FORCEPROP 3 LASTPIN (725 3175) SIG_NAME GND\g
J 0
(735 3185);
DISPLAY 0.659574 (735 3185);
PAINT MONO (735 3185);
DISPLAY INVISIBLE (735 3185);
FORCEPROP 1 LAST PATH I166
J 0
(800 3125);
DISPLAY 0.872340 (800 3125);
PAINT AQUA (800 3125);
DISPLAY INVISIBLE (800 3125);
FORCEPROP 1 LAST HDL_POWER GND
J 1
(750 3050);
DISPLAY 0.872340 (750 3050);
PAINT GREEN (750 3050);
DISPLAY INVISIBLE (750 3050);
FORCEPROP 2 LAST CDS_LIB logical_power
J 0
(725 3125);
DISPLAY INVISIBLE (725 3125);
FORCEADD Q_RES..1
(-1025 3925);
FORCEPROP 1 LAST PART_NUMBER CS00002JB13
J 0
(-1300 3800);
DISPLAY 0.723404 (-1300 3800);
PAINT WHITE (-1300 3800);
DISPLAY INVISIBLE (-1300 3800);
FORCEPROP 0 LAST ROOM USB1_BOM1
J 0
(-1175 3825);
DISPLAY 0.638298 (-1175 3825);
FORCEPROP 1 LAST VALUE 0
J 2
(-875 3925);
DISPLAY 0.723404 (-875 3925);
FORCEPROP 1 LAST PACK_TYPE 0402LF
J 0
(-1000 3875);
DISPLAY 0.723404 (-1000 3875);
FORCEPROP 1 LAST MATERIAL CHIP
J 0
(-1175 3875);
DISPLAY 0.723404 (-1175 3875);
FORCEPROP 1 LAST $LOCATION R3662
J 0
(-1225 3925);
DISPLAY 0.638298 (-1225 3925);
FORCEPROP 1 LASTPIN (-1125 3925) $PN 1
J 0
(-1113 3937);
DISPLAY 0.787234 (-1113 3937);
PAINT MONO (-1113 3937);
FORCEPROP 1 LASTPIN (-925 3925) $PN 2
J 0
(-963 3937);
DISPLAY 0.787234 (-963 3937);
PAINT MONO (-963 3937);
FORCEPROP 1 LAST PATH I167
J 0
(-1075 4075);
DISPLAY 0.978723 (-1075 4075);
PAINT WHITE (-1075 4075);
DISPLAY INVISIBLE (-1075 4075);
FORCEPROP 1 LAST WATTAGE 1/16W
J 2
(-950 3850);
DISPLAY 0.723404 (-950 3850);
PAINT SKYBLUE (-950 3850);
DISPLAY INVISIBLE (-950 3850);
FORCEPROP 1 LAST TOLERANCE 5%
J 0
(-1225 3850);
DISPLAY 0.723404 (-1225 3850);
PAINT SKYBLUE (-1225 3850);
DISPLAY INVISIBLE (-1225 3850);
FORCEPROP 2 LAST CDS_LIB pure_quanta
J 0
(-1025 3925);
DISPLAY INVISIBLE (-1025 3925);
FORCEPROP 0 LAST CDS_LOCATION R3662
J 0
(-875 3975);
DISPLAY 1.021277 (-875 3975);
DISPLAY INVISIBLE (-875 3975);
FORCEPROP 0 LAST $SEC 1
J 0
(-875 3975);
DISPLAY 0.680851 (-875 3975);
PAINT MONO (-875 3975);
DISPLAY INVISIBLE (-875 3975);
FORCEPROP 0 LAST CDS_SEC 1
J 0
(-875 3975);
DISPLAY 1.021277 (-875 3975);
DISPLAY INVISIBLE (-875 3975);
FORCEADD OFFPAGE..1
(-975 3775);
PAINT AQUA (-975 3775);
FORCEPROP 2 LAST $XR0 152 
J 0
(-1257 3775);
DISPLAY 0.638298 (-1257 3775);
PAINT MONO (-1257 3775);
FORCEPROP 2 LAST PATH I168
J 0
(-1150 3825);
DISPLAY 1.021277 (-1150 3825);
DISPLAY INVISIBLE (-1150 3825);
FORCEPROP 1 LAST COMMENT_BODY TRUE
J 0
(-850 3675);
DISPLAY 0.872340 (-850 3675);
PAINT GREEN (-850 3675);
DISPLAY INVISIBLE (-850 3675);
FORCEPROP 1 LAST OFFPAGE TRUE
J 0
(-650 3650);
DISPLAY 0.872340 (-650 3650);
PAINT AQUA (-650 3650);
DISPLAY INVISIBLE (-650 3650);
FORCEPROP 2 LAST CDS_LIB standard
J 0
(-975 3775);
DISPLAY INVISIBLE (-975 3775);
FORCEADD OFFPAGE..1
(-975 3725);
PAINT AQUA (-975 3725);
FORCEPROP 2 LAST $XR0 152 
J 0
(-1257 3725);
DISPLAY 0.638298 (-1257 3725);
PAINT MONO (-1257 3725);
FORCEPROP 2 LAST PATH I169
J 0
(-1150 3775);
DISPLAY 1.021277 (-1150 3775);
DISPLAY INVISIBLE (-1150 3775);
FORCEPROP 1 LAST COMMENT_BODY TRUE
J 0
(-850 3625);
DISPLAY 0.872340 (-850 3625);
PAINT GREEN (-850 3625);
DISPLAY INVISIBLE (-850 3625);
FORCEPROP 1 LAST OFFPAGE TRUE
J 0
(-650 3600);
DISPLAY 0.872340 (-650 3600);
PAINT AQUA (-650 3600);
DISPLAY INVISIBLE (-650 3600);
FORCEPROP 2 LAST CDS_LIB standard
J 0
(-975 3725);
DISPLAY INVISIBLE (-975 3725);
FORCEADD OFFPAGE..1
(-975 3675);
PAINT AQUA (-975 3675);
FORCEPROP 2 LAST $XR0 152 
J 0
(-1257 3675);
DISPLAY 0.638298 (-1257 3675);
PAINT MONO (-1257 3675);
FORCEPROP 2 LAST PATH I170
J 0
(-1150 3725);
DISPLAY 1.021277 (-1150 3725);
DISPLAY INVISIBLE (-1150 3725);
FORCEPROP 1 LAST COMMENT_BODY TRUE
J 0
(-850 3575);
DISPLAY 0.872340 (-850 3575);
PAINT GREEN (-850 3575);
DISPLAY INVISIBLE (-850 3575);
FORCEPROP 1 LAST OFFPAGE TRUE
J 0
(-650 3550);
DISPLAY 0.872340 (-650 3550);
PAINT AQUA (-650 3550);
DISPLAY INVISIBLE (-650 3550);
FORCEPROP 2 LAST CDS_LIB standard
J 0
(-975 3675);
DISPLAY INVISIBLE (-975 3675);
FORCEADD OFFPAGE..1
(-975 3625);
PAINT AQUA (-975 3625);
FORCEPROP 2 LAST $XR0 152 
J 0
(-1257 3625);
DISPLAY 0.638298 (-1257 3625);
PAINT MONO (-1257 3625);
FORCEPROP 2 LAST PATH I171
J 0
(-1150 3675);
DISPLAY 1.021277 (-1150 3675);
DISPLAY INVISIBLE (-1150 3675);
FORCEPROP 1 LAST COMMENT_BODY TRUE
J 0
(-850 3525);
DISPLAY 0.872340 (-850 3525);
PAINT GREEN (-850 3525);
DISPLAY INVISIBLE (-850 3525);
FORCEPROP 1 LAST OFFPAGE TRUE
J 0
(-650 3500);
DISPLAY 0.872340 (-650 3500);
PAINT AQUA (-650 3500);
DISPLAY INVISIBLE (-650 3500);
FORCEPROP 2 LAST CDS_LIB standard
J 0
(-975 3625);
DISPLAY INVISIBLE (-975 3625);
FORCEADD Q_RES..2
(-750 3075);
FORCEPROP 1 LAST PART_NUMBER CS41002FB09
J 0
(-710 2950);
DISPLAY 0.468085 (-710 2950);
DISPLAY INVISIBLE (-710 2950);
FORCEPROP 1 LAST VALUE 100K
J 0
(-705 3150);
DISPLAY 0.468085 (-705 3150);
FORCEPROP 1 LAST TOLERANCE 1%
J 0
(-705 3100);
DISPLAY 0.468085 (-705 3100);
FORCEPROP 1 LAST WATTAGE 1/16W
J 0
(-710 3050);
DISPLAY 0.468085 (-710 3050);
FORCEPROP 1 LAST MATERIAL CHIP
J 0
(-710 3000);
DISPLAY 0.468085 (-710 3000);
FORCEPROP 1 LAST PACK_TYPE 0402LF
J 0
(-710 2900);
DISPLAY 0.468085 (-710 2900);
FORCEPROP 0 LAST ROOM USB1_BOM1
J 0
(-700 2850);
DISPLAY 0.638298 (-700 2850);
FORCEPROP 1 LAST $LOCATION R3665
J 0
(-705 3200);
DISPLAY 0.510638 (-705 3200);
FORCEPROP 1 LASTPIN (-750 3175) $PN 1
J 0
(-745 3137);
DISPLAY 0.787234 (-745 3137);
PAINT MONO (-745 3137);
FORCEPROP 1 LASTPIN (-750 2975) $PN 2
J 0
(-745 2985);
DISPLAY 0.787234 (-745 2985);
PAINT MONO (-745 2985);
FORCEPROP 1 LAST PATH I182
J 0
(-700 3250);
DISPLAY 0.978723 (-700 3250);
PAINT WHITE (-700 3250);
DISPLAY INVISIBLE (-700 3250);
FORCEPROP 2 LAST CDS_LIB pure_quanta
J 0
(-750 3075);
DISPLAY INVISIBLE (-750 3075);
FORCEPROP 0 LAST CDS_LOCATION R3665
J 0
(-700 3250);
DISPLAY 1.021277 (-700 3250);
DISPLAY INVISIBLE (-700 3250);
FORCEPROP 0 LAST $SEC 1
J 0
(-700 3250);
DISPLAY 0.680851 (-700 3250);
PAINT MONO (-700 3250);
DISPLAY INVISIBLE (-700 3250);
FORCEPROP 0 LAST CDS_SEC 1
J 0
(-700 3250);
DISPLAY 1.021277 (-700 3250);
DISPLAY INVISIBLE (-700 3250);
FORCEADD UNIVERSAL_GND..1
(-750 2800);
FORCEPROP 3 LASTPIN (-750 2850) SIG_NAME GND\g
J 0
(-740 2860);
DISPLAY 0.659574 (-740 2860);
PAINT MONO (-740 2860);
DISPLAY INVISIBLE (-740 2860);
FORCEPROP 1 LAST PATH I183
J 0
(-675 2800);
DISPLAY 0.872340 (-675 2800);
PAINT AQUA (-675 2800);
DISPLAY INVISIBLE (-675 2800);
FORCEPROP 1 LAST HDL_POWER GND
J 1
(-725 2725);
DISPLAY 0.872340 (-725 2725);
PAINT GREEN (-725 2725);
DISPLAY INVISIBLE (-725 2725);
FORCEPROP 2 LAST CDS_LIB logical_power
J 0
(-750 2800);
DISPLAY INVISIBLE (-750 2800);
FORCEADD OFFPAGE..1
(-875 3375);
PAINT AQUA (-875 3375);
FORCEPROP 2 LAST $XR0 152 
J 0
(-1187 3375);
DISPLAY 0.638298 (-1187 3375);
PAINT MONO (-1187 3375);
FORCEPROP 2 LAST PATH I184
J 0
(-825 3450);
DISPLAY 1.021277 (-825 3450);
DISPLAY INVISIBLE (-825 3450);
FORCEPROP 1 LAST COMMENT_BODY TRUE
J 0
(-750 3275);
DISPLAY 0.872340 (-750 3275);
PAINT GREEN (-750 3275);
DISPLAY INVISIBLE (-750 3275);
FORCEPROP 1 LAST OFFPAGE TRUE
J 0
(-550 3250);
DISPLAY 0.872340 (-550 3250);
PAINT AQUA (-550 3250);
DISPLAY INVISIBLE (-550 3250);
FORCEPROP 2 LAST CDS_LIB standard
J 0
(-875 3375);
DISPLAY INVISIBLE (-875 3375);
FORCEADD UNIVERSAL_POWER..1
R 2
(-4150 3400);
FORCEPROP 3 LASTPIN (-4150 3350) SIG_NAME P3V3_AUX\g
J 0
(-4140 3360);
DISPLAY 0.659574 (-4140 3360);
PAINT MONO (-4140 3360);
DISPLAY INVISIBLE (-4140 3360);
FORCEPROP 1 LAST HDL_POWER P3V3_AUX
J 1
(-4150 3450);
DISPLAY 0.723404 (-4150 3450);
PAINT GREEN (-4150 3450);
FORCEPROP 1 LAST PATH I185
J 2
(-4200 3425);
DISPLAY 0.872340 (-4200 3425);
PAINT AQUA (-4200 3425);
DISPLAY INVISIBLE (-4200 3425);
FORCEPROP 2 LAST CDS_LIB logical_power
J 0
(-4150 3400);
DISPLAY INVISIBLE (-4150 3400);
FORCEADD Q_RES..2
(-4150 2950);
FORCEPROP 1 LAST PART_NUMBER CS31002FB08
J 0
(-4110 2825);
DISPLAY 0.723404 (-4110 2825);
PAINT WHITE (-4110 2825);
DISPLAY INVISIBLE (-4110 2825);
FORCEPROP 0 LAST ROOM USB1_BOM1
J 0
(-4100 3175);
DISPLAY 1.021277 (-4100 3175);
FORCEPROP 1 LAST MATERIAL CHIP
J 0
(-4110 2875);
DISPLAY 0.723404 (-4110 2875);
PAINT SKYBLUE (-4110 2875);
FORCEPROP 1 LAST TOLERANCE 1%
J 0
(-4105 2975);
DISPLAY 0.723404 (-4105 2975);
PAINT SKYBLUE (-4105 2975);
FORCEPROP 1 LAST WATTAGE 1/16W
J 0
(-4110 2925);
DISPLAY 0.723404 (-4110 2925);
PAINT SKYBLUE (-4110 2925);
FORCEPROP 1 LAST VALUE 10K
J 0
(-4105 3025);
DISPLAY 0.723404 (-4105 3025);
PAINT SKYBLUE (-4105 3025);
FORCEPROP 1 LAST PACK_TYPE 0402LF
J 0
(-4110 2775);
DISPLAY 0.723404 (-4110 2775);
PAINT SKYBLUE (-4110 2775);
FORCEPROP 1 LAST $LOCATION R3663
J 0
(-4105 3075);
DISPLAY 0.978723 (-4105 3075);
FORCEPROP 1 LASTPIN (-4150 3050) $PN 1
J 0
(-4145 3012);
DISPLAY 0.787234 (-4145 3012);
PAINT MONO (-4145 3012);
FORCEPROP 1 LASTPIN (-4150 2850) $PN 2
J 0
(-4145 2860);
DISPLAY 0.787234 (-4145 2860);
PAINT MONO (-4145 2860);
FORCEPROP 1 LAST PATH I186
J 0
(-4100 3125);
DISPLAY 0.978723 (-4100 3125);
PAINT WHITE (-4100 3125);
DISPLAY INVISIBLE (-4100 3125);
FORCEPROP 2 LAST CDS_LIB pure_quanta
J 0
(-4150 2950);
DISPLAY INVISIBLE (-4150 2950);
FORCEPROP 0 LAST CDS_LOCATION R3663
J 0
(-4100 3125);
DISPLAY 1.021277 (-4100 3125);
DISPLAY INVISIBLE (-4100 3125);
FORCEPROP 0 LAST $SEC 1
J 0
(-4100 3125);
DISPLAY 0.680851 (-4100 3125);
PAINT MONO (-4100 3125);
DISPLAY INVISIBLE (-4100 3125);
FORCEPROP 0 LAST CDS_SEC 1
J 0
(-4100 3125);
DISPLAY 1.021277 (-4100 3125);
DISPLAY INVISIBLE (-4100 3125);
FORCEADD Q_RES..2
(-4150 2350);
FORCEPROP 1 LAST PART_NUMBER CS31002FB08
J 0
(-4110 2225);
DISPLAY 0.723404 (-4110 2225);
PAINT WHITE (-4110 2225);
DISPLAY INVISIBLE (-4110 2225);
FORCEPROP 1 LAST MATERIAL EMPTY
J 0
(-4110 2275);
DISPLAY 0.723404 (-4110 2275);
PAINT RED (-4110 2275);
FORCEPROP 1 LAST WATTAGE 1/16W
J 0
(-4110 2325);
DISPLAY 0.723404 (-4110 2325);
PAINT SKYBLUE (-4110 2325);
FORCEPROP 1 LAST VALUE 10K
J 0
(-4105 2425);
DISPLAY 0.723404 (-4105 2425);
PAINT SKYBLUE (-4105 2425);
FORCEPROP 1 LAST TOLERANCE 1%
J 0
(-4105 2375);
DISPLAY 0.723404 (-4105 2375);
PAINT SKYBLUE (-4105 2375);
FORCEPROP 1 LAST PACK_TYPE 0402LF
J 0
(-4110 2175);
DISPLAY 0.723404 (-4110 2175);
PAINT SKYBLUE (-4110 2175);
FORCEPROP 1 LAST $LOCATION R3664
J 0
(-4105 2475);
DISPLAY 0.978723 (-4105 2475);
FORCEPROP 1 LASTPIN (-4150 2450) $PN 1
J 0
(-4145 2412);
DISPLAY 0.787234 (-4145 2412);
PAINT MONO (-4145 2412);
FORCEPROP 1 LASTPIN (-4150 2250) $PN 2
J 0
(-4145 2260);
DISPLAY 0.787234 (-4145 2260);
PAINT MONO (-4145 2260);
FORCEPROP 1 LAST PATH I187
J 0
(-4100 2525);
DISPLAY 0.978723 (-4100 2525);
PAINT WHITE (-4100 2525);
DISPLAY INVISIBLE (-4100 2525);
FORCEPROP 2 LAST CDS_LIB pure_quanta
J 0
(-4150 2350);
DISPLAY INVISIBLE (-4150 2350);
FORCEPROP 0 LAST CDS_LOCATION R3664
J 0
(-4100 2525);
DISPLAY 1.021277 (-4100 2525);
DISPLAY INVISIBLE (-4100 2525);
FORCEPROP 0 LAST $SEC 1
J 0
(-4100 2525);
DISPLAY 0.680851 (-4100 2525);
PAINT MONO (-4100 2525);
DISPLAY INVISIBLE (-4100 2525);
FORCEPROP 0 LAST CDS_SEC 1
J 0
(-4100 2525);
DISPLAY 1.021277 (-4100 2525);
DISPLAY INVISIBLE (-4100 2525);
FORCEADD UNIVERSAL_GND..1
(-4150 1925);
FORCEPROP 3 LASTPIN (-4150 1975) SIG_NAME GND\g
J 0
(-4140 1985);
DISPLAY 0.659574 (-4140 1985);
PAINT MONO (-4140 1985);
DISPLAY INVISIBLE (-4140 1985);
FORCEPROP 1 LAST PATH I188
J 0
(-4075 1925);
DISPLAY 0.872340 (-4075 1925);
PAINT AQUA (-4075 1925);
DISPLAY INVISIBLE (-4075 1925);
FORCEPROP 1 LAST HDL_POWER GND
J 1
(-4125 1850);
DISPLAY 0.872340 (-4125 1850);
PAINT GREEN (-4125 1850);
DISPLAY INVISIBLE (-4125 1850);
FORCEPROP 2 LAST CDS_LIB logical_power
J 0
(-4150 1925);
DISPLAY INVISIBLE (-4150 1925);
FORCEADD OFFPAGE..5
R 2
(-3025 2625);
PAINT AQUA (-3025 2625);
FORCEPROP 2 LAST $XR0 152 
J 0
(-2836 2625);
DISPLAY 0.638298 (-2836 2625);
PAINT MONO (-2836 2625);
FORCEPROP 2 LAST PATH I189
J 2
(-3075 2700);
DISPLAY 1.021277 (-3075 2700);
DISPLAY INVISIBLE (-3075 2700);
FORCEPROP 1 LAST COMMENT_BODY TRUE
J 2
(-3125 2550);
DISPLAY 1.170213 (-3125 2550);
PAINT GREEN (-3125 2550);
DISPLAY INVISIBLE (-3125 2550);
FORCEPROP 1 LAST OFFPAGE TRUE
J 2
(-3350 2500);
DISPLAY 0.872340 (-3350 2500);
PAINT AQUA (-3350 2500);
DISPLAY INVISIBLE (-3350 2500);
FORCEPROP 2 LAST CDS_LIB standard
J 2
(-3025 2625);
DISPLAY INVISIBLE (-3025 2625);
FORCEADD OFFPAGE..5
R 2
(-825 2275);
FORCEPROP 2 LAST $XR0 152 
J 0
(-636 2275);
DISPLAY 0.638298 (-636 2275);
PAINT MONO (-636 2275);
FORCEPROP 2 LAST PATH I190
J 0
(-650 2350);
DISPLAY 1.021277 (-650 2350);
DISPLAY INVISIBLE (-650 2350);
FORCEPROP 1 LAST COMMENT_BODY TRUE
J 2
(-925 2200);
DISPLAY 0.872340 (-925 2200);
PAINT GREEN (-925 2200);
DISPLAY INVISIBLE (-925 2200);
FORCEPROP 1 LAST OFFPAGE TRUE
J 2
(-1150 2150);
DISPLAY 0.872340 (-1150 2150);
PAINT GREEN (-1150 2150);
DISPLAY INVISIBLE (-1150 2150);
FORCEPROP 2 LAST CDS_LIB standard
J 2
(-825 2275);
DISPLAY INVISIBLE (-825 2275);
FORCEADD OFFPAGE..5
R 2
(-825 2125);
FORCEPROP 2 LAST $XR0 152 
J 0
(-636 2125);
DISPLAY 0.638298 (-636 2125);
PAINT MONO (-636 2125);
FORCEPROP 2 LAST PATH I191
J 0
(-650 2200);
DISPLAY 1.021277 (-650 2200);
DISPLAY INVISIBLE (-650 2200);
FORCEPROP 1 LAST COMMENT_BODY TRUE
J 2
(-925 2050);
DISPLAY 0.872340 (-925 2050);
PAINT GREEN (-925 2050);
DISPLAY INVISIBLE (-925 2050);
FORCEPROP 1 LAST OFFPAGE TRUE
J 2
(-1150 2000);
DISPLAY 0.872340 (-1150 2000);
PAINT GREEN (-1150 2000);
DISPLAY INVISIBLE (-1150 2000);
FORCEPROP 2 LAST CDS_LIB standard
J 0
(-825 2125);
DISPLAY INVISIBLE (-825 2125);
FORCEADD OFFPAGE..5
R 2
(-825 2000);
FORCEPROP 2 LAST $XR0 152 
J 0
(-636 2000);
DISPLAY 0.638298 (-636 2000);
PAINT MONO (-636 2000);
FORCEPROP 2 LAST PATH I192
J 0
(-650 2075);
DISPLAY 1.021277 (-650 2075);
DISPLAY INVISIBLE (-650 2075);
FORCEPROP 1 LAST COMMENT_BODY TRUE
J 2
(-925 1925);
DISPLAY 0.872340 (-925 1925);
PAINT GREEN (-925 1925);
DISPLAY INVISIBLE (-925 1925);
FORCEPROP 1 LAST OFFPAGE TRUE
J 2
(-1150 1875);
DISPLAY 0.872340 (-1150 1875);
PAINT GREEN (-1150 1875);
DISPLAY INVISIBLE (-1150 1875);
FORCEPROP 2 LAST CDS_LIB standard
J 0
(-825 2000);
DISPLAY INVISIBLE (-825 2000);
FORCEADD OFFPAGE..5
R 2
(-825 1875);
FORCEPROP 2 LAST $XR0 152 
J 0
(-636 1875);
DISPLAY 0.638298 (-636 1875);
PAINT MONO (-636 1875);
FORCEPROP 2 LAST PATH I193
J 0
(-650 1950);
DISPLAY 1.021277 (-650 1950);
DISPLAY INVISIBLE (-650 1950);
FORCEPROP 1 LAST COMMENT_BODY TRUE
J 2
(-925 1800);
DISPLAY 0.872340 (-925 1800);
PAINT GREEN (-925 1800);
DISPLAY INVISIBLE (-925 1800);
FORCEPROP 1 LAST OFFPAGE TRUE
J 2
(-1150 1750);
DISPLAY 0.872340 (-1150 1750);
PAINT GREEN (-1150 1750);
DISPLAY INVISIBLE (-1150 1750);
FORCEPROP 2 LAST CDS_LIB standard
J 0
(-825 1875);
DISPLAY INVISIBLE (-825 1875);
FORCEADD Q_RES..1
(-1550 2275);
FORCEPROP 1 LAST PART_NUMBER CS31002FB08
J 0
(-1725 2125);
DISPLAY 0.638298 (-1725 2125);
DISPLAY INVISIBLE (-1725 2125);
FORCEPROP 1 LAST MATERIAL EMPTY
J 0
(-1525 2225);
DISPLAY 0.638298 (-1525 2225);
PAINT RED (-1525 2225);
FORCEPROP 1 LAST VALUE 10K
J 2
(-1575 2225);
DISPLAY 0.638298 (-1575 2225);
FORCEPROP 1 LAST $LOCATION R3656
J 0
(-1700 2300);
DISPLAY 0.638298 (-1700 2300);
FORCEPROP 1 LASTPIN (-1650 2275) $PN 1
J 0
(-1638 2287);
DISPLAY 0.787234 (-1638 2287);
PAINT MONO (-1638 2287);
FORCEPROP 1 LASTPIN (-1450 2275) $PN 2
J 0
(-1488 2287);
DISPLAY 0.787234 (-1488 2287);
PAINT MONO (-1488 2287);
FORCEPROP 1 LAST PATH I194
J 0
(-1600 2425);
DISPLAY 0.978723 (-1600 2425);
PAINT WHITE (-1600 2425);
DISPLAY INVISIBLE (-1600 2425);
FORCEPROP 2 LAST CDS_LIB pure_quanta
J 0
(-1550 2275);
DISPLAY INVISIBLE (-1550 2275);
FORCEPROP 1 LAST PACK_TYPE 0402LF
J 0
(-1450 2225);
DISPLAY 0.638298 (-1450 2225);
DISPLAY INVISIBLE (-1450 2225);
FORCEPROP 1 LAST TOLERANCE 1%
J 0
(-1550 2225);
DISPLAY 0.638298 (-1550 2225);
DISPLAY INVISIBLE (-1550 2225);
FORCEPROP 1 LAST WATTAGE 1/16W
J 2
(-1575 2175);
DISPLAY 0.638298 (-1575 2175);
DISPLAY INVISIBLE (-1575 2175);
FORCEPROP 0 LAST CDS_LOCATION R3656
J 0
(-1700 2350);
DISPLAY 1.021277 (-1700 2350);
DISPLAY INVISIBLE (-1700 2350);
FORCEPROP 0 LAST $SEC 1
J 0
(-1700 2350);
DISPLAY 0.680851 (-1700 2350);
PAINT MONO (-1700 2350);
DISPLAY INVISIBLE (-1700 2350);
FORCEPROP 0 LAST CDS_SEC 1
J 0
(-1700 2350);
DISPLAY 1.021277 (-1700 2350);
DISPLAY INVISIBLE (-1700 2350);
FORCEADD Q_RES..1
(-1550 2125);
FORCEPROP 1 LAST PART_NUMBER CS31002FB08
J 0
(-1725 1975);
DISPLAY 0.638298 (-1725 1975);
DISPLAY INVISIBLE (-1725 1975);
FORCEPROP 1 LAST VALUE 10K
J 2
(-1575 2075);
DISPLAY 0.638298 (-1575 2075);
FORCEPROP 1 LAST MATERIAL EMPTY
J 0
(-1525 2075);
DISPLAY 0.638298 (-1525 2075);
PAINT RED (-1525 2075);
FORCEPROP 1 LAST $LOCATION R3657
J 0
(-1700 2150);
DISPLAY 0.638298 (-1700 2150);
FORCEPROP 1 LASTPIN (-1650 2125) $PN 1
J 0
(-1638 2137);
DISPLAY 0.787234 (-1638 2137);
PAINT MONO (-1638 2137);
FORCEPROP 1 LASTPIN (-1450 2125) $PN 2
J 0
(-1488 2137);
DISPLAY 0.787234 (-1488 2137);
PAINT MONO (-1488 2137);
FORCEPROP 1 LAST PATH I195
J 0
(-1600 2275);
DISPLAY 0.978723 (-1600 2275);
PAINT WHITE (-1600 2275);
DISPLAY INVISIBLE (-1600 2275);
FORCEPROP 2 LAST CDS_LIB pure_quanta
J 0
(-1550 2125);
DISPLAY INVISIBLE (-1550 2125);
FORCEPROP 1 LAST WATTAGE 1/16W
J 2
(-1575 2025);
DISPLAY 0.638298 (-1575 2025);
DISPLAY INVISIBLE (-1575 2025);
FORCEPROP 1 LAST TOLERANCE 1%
J 0
(-1550 2075);
DISPLAY 0.638298 (-1550 2075);
DISPLAY INVISIBLE (-1550 2075);
FORCEPROP 1 LAST PACK_TYPE 0402LF
J 0
(-1450 2075);
DISPLAY 0.638298 (-1450 2075);
DISPLAY INVISIBLE (-1450 2075);
FORCEPROP 0 LAST CDS_LOCATION R3657
J 0
(-1700 2200);
DISPLAY 1.021277 (-1700 2200);
DISPLAY INVISIBLE (-1700 2200);
FORCEPROP 0 LAST $SEC 1
J 0
(-1700 2200);
DISPLAY 0.680851 (-1700 2200);
PAINT MONO (-1700 2200);
DISPLAY INVISIBLE (-1700 2200);
FORCEPROP 0 LAST CDS_SEC 1
J 0
(-1700 2200);
DISPLAY 1.021277 (-1700 2200);
DISPLAY INVISIBLE (-1700 2200);
FORCEADD Q_RES..1
(-1550 2000);
FORCEPROP 1 LAST PART_NUMBER CS31002FB08
J 0
(-1725 1850);
DISPLAY 0.638298 (-1725 1850);
DISPLAY INVISIBLE (-1725 1850);
FORCEPROP 1 LAST VALUE 10K
J 2
(-1575 1950);
DISPLAY 0.638298 (-1575 1950);
FORCEPROP 1 LAST MATERIAL EMPTY
J 0
(-1525 1950);
DISPLAY 0.638298 (-1525 1950);
PAINT RED (-1525 1950);
FORCEPROP 1 LAST $LOCATION R3658
J 0
(-1700 2025);
DISPLAY 0.638298 (-1700 2025);
FORCEPROP 1 LASTPIN (-1650 2000) $PN 1
J 0
(-1638 2012);
DISPLAY 0.787234 (-1638 2012);
PAINT MONO (-1638 2012);
FORCEPROP 1 LASTPIN (-1450 2000) $PN 2
J 0
(-1488 2012);
DISPLAY 0.787234 (-1488 2012);
PAINT MONO (-1488 2012);
FORCEPROP 1 LAST PATH I196
J 0
(-1600 2150);
DISPLAY 0.978723 (-1600 2150);
PAINT WHITE (-1600 2150);
DISPLAY INVISIBLE (-1600 2150);
FORCEPROP 1 LAST WATTAGE 1/16W
J 2
(-1575 1900);
DISPLAY 0.638298 (-1575 1900);
DISPLAY INVISIBLE (-1575 1900);
FORCEPROP 1 LAST TOLERANCE 1%
J 0
(-1550 1950);
DISPLAY 0.638298 (-1550 1950);
DISPLAY INVISIBLE (-1550 1950);
FORCEPROP 1 LAST PACK_TYPE 0402LF
J 0
(-1450 1950);
DISPLAY 0.638298 (-1450 1950);
DISPLAY INVISIBLE (-1450 1950);
FORCEPROP 2 LAST CDS_LIB pure_quanta
J 0
(-1550 2000);
DISPLAY INVISIBLE (-1550 2000);
FORCEPROP 0 LAST CDS_LOCATION R3658
J 0
(-1700 2075);
DISPLAY 1.021277 (-1700 2075);
DISPLAY INVISIBLE (-1700 2075);
FORCEPROP 0 LAST $SEC 1
J 0
(-1700 2075);
DISPLAY 0.680851 (-1700 2075);
PAINT MONO (-1700 2075);
DISPLAY INVISIBLE (-1700 2075);
FORCEPROP 0 LAST CDS_SEC 1
J 0
(-1700 2075);
DISPLAY 1.021277 (-1700 2075);
DISPLAY INVISIBLE (-1700 2075);
FORCEADD UNIVERSAL_POWER..1
R 2
(-2175 2525);
FORCEPROP 3 LASTPIN (-2175 2475) SIG_NAME P3V3_AUX\g
J 0
(-2165 2485);
DISPLAY 0.659574 (-2165 2485);
PAINT MONO (-2165 2485);
DISPLAY INVISIBLE (-2165 2485);
FORCEPROP 1 LAST HDL_POWER P3V3_AUX
J 1
(-2175 2575);
DISPLAY 0.723404 (-2175 2575);
PAINT GREEN (-2175 2575);
FORCEPROP 1 LAST PATH I197
J 2
(-2225 2550);
DISPLAY 0.872340 (-2225 2550);
PAINT AQUA (-2225 2550);
DISPLAY INVISIBLE (-2225 2550);
FORCEPROP 2 LAST CDS_LIB logical_power
J 0
(-2175 2525);
DISPLAY INVISIBLE (-2175 2525);
FORCEADD Q_RES..1
(-1550 1875);
FORCEPROP 1 LAST PART_NUMBER CS31002FB08
J 0
(-1725 1725);
DISPLAY 0.638298 (-1725 1725);
DISPLAY INVISIBLE (-1725 1725);
FORCEPROP 1 LAST MATERIAL EMPTY
J 0
(-1550 1775);
DISPLAY 0.638298 (-1550 1775);
PAINT RED (-1550 1775);
FORCEPROP 1 LAST TOLERANCE 1%
J 0
(-1550 1825);
DISPLAY 0.638298 (-1550 1825);
FORCEPROP 1 LAST PACK_TYPE 0402LF
J 0
(-1450 1825);
DISPLAY 0.638298 (-1450 1825);
FORCEPROP 1 LAST VALUE 10K
J 2
(-1575 1825);
DISPLAY 0.638298 (-1575 1825);
FORCEPROP 1 LAST WATTAGE 1/16W
J 2
(-1575 1775);
DISPLAY 0.638298 (-1575 1775);
FORCEPROP 1 LAST $LOCATION R3659
J 0
(-1700 1875);
DISPLAY 0.638298 (-1700 1875);
FORCEPROP 1 LASTPIN (-1650 1875) $PN 1
J 0
(-1638 1887);
DISPLAY 0.787234 (-1638 1887);
PAINT MONO (-1638 1887);
FORCEPROP 1 LASTPIN (-1450 1875) $PN 2
J 0
(-1488 1887);
DISPLAY 0.787234 (-1488 1887);
PAINT MONO (-1488 1887);
FORCEPROP 1 LAST PATH I198
J 0
(-1600 2025);
DISPLAY 0.978723 (-1600 2025);
PAINT WHITE (-1600 2025);
DISPLAY INVISIBLE (-1600 2025);
FORCEPROP 2 LAST CDS_LIB pure_quanta
J 0
(-1550 1875);
DISPLAY INVISIBLE (-1550 1875);
FORCEPROP 0 LAST CDS_LOCATION R3659
J 0
(-1700 1925);
DISPLAY 1.021277 (-1700 1925);
DISPLAY INVISIBLE (-1700 1925);
FORCEPROP 0 LAST $SEC 1
J 0
(-1700 1925);
DISPLAY 0.680851 (-1700 1925);
PAINT MONO (-1700 1925);
DISPLAY INVISIBLE (-1700 1925);
FORCEPROP 0 LAST CDS_SEC 1
J 0
(-1700 1925);
DISPLAY 1.021277 (-1700 1925);
DISPLAY INVISIBLE (-1700 1925);
FORCEADD Q_RES..1
(1375 4275);
FORCEPROP 1 LAST PART_NUMBER CS00002JB13
J 0
(1100 4150);
DISPLAY 0.723404 (1100 4150);
PAINT WHITE (1100 4150);
DISPLAY INVISIBLE (1100 4150);
FORCEPROP 0 LAST ROOM USB1_BOM1
J 0
(1500 4325);
DISPLAY 0.808511 (1500 4325);
FORCEPROP 1 LAST MATERIAL CHIP
J 0
(1550 4225);
DISPLAY 0.723404 (1550 4225);
FORCEPROP 1 LAST PACK_TYPE 0402LF
J 0
(1550 4275);
DISPLAY 0.723404 (1550 4275);
FORCEPROP 1 LAST VALUE 0
J 2
(1525 4275);
DISPLAY 0.723404 (1525 4275);
FORCEPROP 1 LAST $LOCATION R3666
J 0
(1125 4275);
DISPLAY 0.638298 (1125 4275);
FORCEPROP 1 LASTPIN (1275 4275) $PN 1
J 0
(1287 4287);
DISPLAY 0.787234 (1287 4287);
PAINT MONO (1287 4287);
FORCEPROP 1 LASTPIN (1475 4275) $PN 2
J 0
(1437 4287);
DISPLAY 0.787234 (1437 4287);
PAINT MONO (1437 4287);
FORCEPROP 1 LAST PATH I199
J 0
(1325 4425);
DISPLAY 0.978723 (1325 4425);
PAINT WHITE (1325 4425);
DISPLAY INVISIBLE (1325 4425);
FORCEPROP 1 LAST WATTAGE 1/16W
J 2
(1450 4200);
DISPLAY 0.723404 (1450 4200);
PAINT SKYBLUE (1450 4200);
DISPLAY INVISIBLE (1450 4200);
FORCEPROP 1 LAST TOLERANCE 5%
J 0
(1175 4200);
DISPLAY 0.723404 (1175 4200);
PAINT SKYBLUE (1175 4200);
DISPLAY INVISIBLE (1175 4200);
FORCEPROP 2 LAST CDS_LIB pure_quanta
J 0
(1375 4275);
DISPLAY INVISIBLE (1375 4275);
FORCEPROP 0 LAST CDS_LOCATION R3666
J 0
(1550 4325);
DISPLAY 1.021277 (1550 4325);
DISPLAY INVISIBLE (1550 4325);
FORCEPROP 0 LAST $SEC 1
J 0
(1550 4325);
DISPLAY 0.680851 (1550 4325);
PAINT MONO (1550 4325);
DISPLAY INVISIBLE (1550 4325);
FORCEPROP 0 LAST CDS_SEC 1
J 0
(1550 4325);
DISPLAY 1.021277 (1550 4325);
DISPLAY INVISIBLE (1550 4325);
FORCEADD Q_XTAL_4P_13BI_24GND..1
(4025 4550);
FORCEPROP 1 LAST PART_NUMBER BG6120000E0
J 0
(3892 4825);
DISPLAY 0.723404 (3892 4825);
PAINT GREEN (3892 4825);
DISPLAY INVISIBLE (3892 4825);
FORCEPROP 2 LAST VALUE 12MHZ
J 0
(3900 4950);
DISPLAY 1.021277 (3900 4950);
FORCEPROP 2 LAST PART_TYPE SMLF
J 0
(3900 5000);
DISPLAY 1.021277 (3900 5000);
FORCEPROP 1 LAST MATERIAL MISC
J 0
(3892 4729);
DISPLAY 0.723404 (3892 4729);
PAINT GREEN (3892 4729);
FORCEPROP 2 LAST ROOM USB1_BOM1
J 0
(3900 5050);
DISPLAY 1.021277 (3900 5050);
FORCEPROP 1 LAST LOCATION Y4
J 0
(3892 4916);
DISPLAY 0.723404 (3892 4916);
PAINT GREEN (3892 4916);
FORCEPROP 0 LASTPIN (3750 4425) $PN 2
J 2
(3740 4435);
DISPLAY 0.680851 (3740 4435);
PAINT MONO (3740 4435);
FORCEPROP 0 LASTPIN (4300 4425) $PN 4
J 0
(4310 4435);
DISPLAY 0.680851 (4310 4435);
PAINT MONO (4310 4435);
FORCEPROP 0 LASTPIN (3750 4625) $PN 1
J 2
(3740 4635);
DISPLAY 0.680851 (3740 4635);
PAINT MONO (3740 4635);
FORCEPROP 0 LASTPIN (4300 4625) $PN 3
J 0
(4310 4635);
DISPLAY 0.680851 (4310 4635);
PAINT MONO (4310 4635);
FORCEPROP 1 LAST PATH I200
J 0
(4150 4375);
DISPLAY 0.723404 (4150 4375);
PAINT GREEN (4150 4375);
DISPLAY INVISIBLE (4150 4375);
FORCEPROP 1 LAST CDS_LMAN_SYM_OUTLINE -125,175,125,-175
J 0
(4025 4550);
DISPLAY 0.468085 (4025 4550);
PAINT GREEN (4025 4550);
DISPLAY INVISIBLE (4025 4550);
FORCEPROP 1 LAST PIN_NAMES_ROTATE True
J 0
(4025 4550);
DISPLAY 0.489362 (4025 4550);
PAINT GREEN (4025 4550);
DISPLAY INVISIBLE (4025 4550);
FORCEPROP 2 LAST CDS_LIB pure_quanta
J 0
(4025 4550);
DISPLAY INVISIBLE (4025 4550);
FORCEPROP 0 LAST $SEC 1
J 0
(3900 5050);
DISPLAY 0.680851 (3900 5050);
PAINT MONO (3900 5050);
DISPLAY INVISIBLE (3900 5050);
FORCEPROP 0 LAST CDS_SEC 1
J 0
(3900 5050);
DISPLAY 1.021277 (3900 5050);
DISPLAY INVISIBLE (3900 5050);
FORCEADD Q_RES..1
R 1
(-1900 3100);
FORCEPROP 1 LAST PART_NUMBER CS34702BB05
J 0
(-1825 2975);
DISPLAY 0.638298 (-1825 2975);
DISPLAY INVISIBLE (-1825 2975);
FORCEPROP 1 LAST VALUE 47K
J 2
(-1725 3175);
DISPLAY 0.638298 (-1725 3175);
FORCEPROP 1 LAST PACK_TYPE 0402LF
J 0
(-1825 2925);
DISPLAY 0.638298 (-1825 2925);
FORCEPROP 1 LAST MATERIAL EMPTY
J 0
(-1825 3025);
DISPLAY 0.638298 (-1825 3025);
PAINT RED (-1825 3025);
FORCEPROP 1 LAST WATTAGE 1/16W
J 2
(-1675 3075);
DISPLAY 0.638298 (-1675 3075);
FORCEPROP 1 LAST TOLERANCE 0.1%
J 0
(-1825 3125);
DISPLAY 0.638298 (-1825 3125);
FORCEPROP 1 LAST LOCATION R3661
J 0
(-1825 3225);
DISPLAY 0.638298 (-1825 3225);
FORCEPROP 1 LASTPIN (-1900 3000) $PN 1
R 1
J 0
(-1912 3012);
DISPLAY 0.787234 (-1912 3012);
PAINT MONO (-1912 3012);
FORCEPROP 1 LASTPIN (-1900 3200) $PN 2
R 1
J 0
(-1912 3162);
DISPLAY 0.787234 (-1912 3162);
PAINT MONO (-1912 3162);
FORCEPROP 1 LAST PATH I201
R 1
J 0
(-2050 3050);
DISPLAY 0.978723 (-2050 3050);
PAINT WHITE (-2050 3050);
DISPLAY INVISIBLE (-2050 3050);
FORCEPROP 2 LAST CDS_LIB pure_quanta
R 1
J 0
(-1900 3100);
DISPLAY INVISIBLE (-1900 3100);
FORCEPROP 0 LAST $SEC 1
R 1
J 0
(-1825 3275);
DISPLAY 0.680851 (-1825 3275);
PAINT MONO (-1825 3275);
DISPLAY INVISIBLE (-1825 3275);
FORCEPROP 0 LAST CDS_SEC 1
R 1
J 0
(-1825 3275);
DISPLAY 1.021277 (-1825 3275);
DISPLAY INVISIBLE (-1825 3275);
FORCEADD Q_RES..2
(3625 3675);
FORCEPROP 1 LAST PART_NUMBER CS04992FB07
J 0
(3665 3550);
DISPLAY 0.510638 (3665 3550);
DISPLAY INVISIBLE (3665 3550);
FORCEPROP 1 LAST VALUE 49.9
J 0
(3675 3650);
DISPLAY 0.510638 (3675 3650);
FORCEPROP 1 LAST MATERIAL EMPTY
J 0
(3665 3600);
DISPLAY 0.510638 (3665 3600);
PAINT RED (3665 3600);
FORCEPROP 1 LAST $LOCATION R4420
J 0
(3675 3700);
DISPLAY 0.638298 (3675 3700);
FORCEPROP 1 LASTPIN (3625 3775) $PN 1
J 0
(3630 3737);
DISPLAY 0.787234 (3630 3737);
PAINT MONO (3630 3737);
FORCEPROP 1 LASTPIN (3625 3575) $PN 2
J 0
(3630 3585);
DISPLAY 0.787234 (3630 3585);
PAINT MONO (3630 3585);
FORCEPROP 1 LAST PATH I202
J 0
(3675 3850);
DISPLAY 0.978723 (3675 3850);
PAINT WHITE (3675 3850);
DISPLAY INVISIBLE (3675 3850);
FORCEPROP 1 LAST PACK_TYPE 0402LF
J 0
(3675 3500);
DISPLAY 0.510638 (3675 3500);
DISPLAY INVISIBLE (3675 3500);
FORCEPROP 1 LAST TOLERANCE 1%
J 0
(3670 3700);
DISPLAY 0.510638 (3670 3700);
DISPLAY INVISIBLE (3670 3700);
FORCEPROP 1 LAST WATTAGE 1/16W
J 0
(3665 3650);
DISPLAY 0.510638 (3665 3650);
DISPLAY INVISIBLE (3665 3650);
FORCEPROP 2 LAST CDS_LIB pure_quanta
J 0
(3625 3675);
DISPLAY INVISIBLE (3625 3675);
FORCEPROP 0 LAST CDS_LOCATION R4420
J 0
(3675 3750);
DISPLAY 1.021277 (3675 3750);
DISPLAY INVISIBLE (3675 3750);
FORCEPROP 0 LAST $SEC 1
J 0
(3675 3750);
DISPLAY 0.680851 (3675 3750);
PAINT MONO (3675 3750);
DISPLAY INVISIBLE (3675 3750);
FORCEPROP 0 LAST CDS_SEC 1
J 0
(3675 3750);
DISPLAY 1.021277 (3675 3750);
DISPLAY INVISIBLE (3675 3750);
FORCEADD Q_RES..2
(3450 3675);
FORCEPROP 1 LAST PART_NUMBER CS04992FB07
J 0
(3490 3550);
DISPLAY 0.510638 (3490 3550);
DISPLAY INVISIBLE (3490 3550);
FORCEPROP 1 LAST VALUE 49.9
J 0
(3500 3650);
DISPLAY 0.510638 (3500 3650);
FORCEPROP 1 LAST MATERIAL EMPTY
J 0
(3490 3600);
DISPLAY 0.510638 (3490 3600);
PAINT RED (3490 3600);
FORCEPROP 1 LAST $LOCATION R4419
J 0
(3500 3700);
DISPLAY 0.510638 (3500 3700);
FORCEPROP 1 LASTPIN (3450 3775) $PN 1
J 0
(3455 3737);
DISPLAY 0.787234 (3455 3737);
PAINT MONO (3455 3737);
FORCEPROP 1 LASTPIN (3450 3575) $PN 2
J 0
(3455 3585);
DISPLAY 0.787234 (3455 3585);
PAINT MONO (3455 3585);
FORCEPROP 1 LAST PATH I203
J 0
(3500 3850);
DISPLAY 0.978723 (3500 3850);
PAINT WHITE (3500 3850);
DISPLAY INVISIBLE (3500 3850);
FORCEPROP 1 LAST WATTAGE 1/16W
J 0
(3490 3650);
DISPLAY 0.510638 (3490 3650);
DISPLAY INVISIBLE (3490 3650);
FORCEPROP 1 LAST TOLERANCE 1%
J 0
(3495 3700);
DISPLAY 0.510638 (3495 3700);
DISPLAY INVISIBLE (3495 3700);
FORCEPROP 1 LAST PACK_TYPE 0402LF
J 0
(3500 3500);
DISPLAY 0.510638 (3500 3500);
DISPLAY INVISIBLE (3500 3500);
FORCEPROP 2 LAST CDS_LIB pure_quanta
J 0
(3450 3675);
DISPLAY INVISIBLE (3450 3675);
FORCEPROP 0 LAST CDS_LOCATION R4419
J 0
(3500 3725);
DISPLAY 1.021277 (3500 3725);
DISPLAY INVISIBLE (3500 3725);
FORCEPROP 0 LAST $SEC 1
J 0
(3500 3725);
DISPLAY 0.680851 (3500 3725);
PAINT MONO (3500 3725);
DISPLAY INVISIBLE (3500 3725);
FORCEPROP 0 LAST CDS_SEC 1
J 0
(3500 3725);
DISPLAY 1.021277 (3500 3725);
DISPLAY INVISIBLE (3500 3725);
FORCEADD UNIVERSAL_GND..1
(3625 3450);
FORCEPROP 3 LASTPIN (3625 3500) SIG_NAME GND\g
J 0
(3635 3510);
DISPLAY 0.659574 (3635 3510);
PAINT MONO (3635 3510);
DISPLAY INVISIBLE (3635 3510);
FORCEPROP 2 LAST CDS_LIB logical_power
J 0
(3625 3450);
DISPLAY INVISIBLE (3625 3450);
FORCEPROP 1 LAST HDL_POWER GND
J 1
(3650 3375);
DISPLAY 0.872340 (3650 3375);
PAINT GREEN (3650 3375);
DISPLAY INVISIBLE (3650 3375);
FORCEPROP 1 LAST PATH I204
J 0
(3700 3450);
DISPLAY 0.872340 (3700 3450);
PAINT AQUA (3700 3450);
DISPLAY INVISIBLE (3700 3450);
FORCEADD UNIVERSAL_GND..1
(3450 3450);
FORCEPROP 3 LASTPIN (3450 3500) SIG_NAME GND\g
J 0
(3460 3510);
DISPLAY 0.659574 (3460 3510);
PAINT MONO (3460 3510);
DISPLAY INVISIBLE (3460 3510);
FORCEPROP 2 LAST CDS_LIB logical_power
J 0
(3450 3450);
DISPLAY INVISIBLE (3450 3450);
FORCEPROP 1 LAST HDL_POWER GND
J 1
(3475 3375);
DISPLAY 0.872340 (3475 3375);
PAINT GREEN (3475 3375);
DISPLAY INVISIBLE (3475 3375);
FORCEPROP 1 LAST PATH I205
J 0
(3525 3450);
DISPLAY 0.872340 (3525 3450);
PAINT AQUA (3525 3450);
DISPLAY INVISIBLE (3525 3450);
FORCEADD Q_RES..2
(-2275 1025);
FORCEPROP 1 LAST PART_NUMBER CS04992FB07
J 0
(-2235 900);
DISPLAY 0.510638 (-2235 900);
DISPLAY INVISIBLE (-2235 900);
FORCEPROP 1 LAST VALUE 49.9
J 0
(-2225 1000);
DISPLAY 0.510638 (-2225 1000);
FORCEPROP 1 LAST MATERIAL EMPTY
J 0
(-2235 950);
DISPLAY 0.510638 (-2235 950);
PAINT RED (-2235 950);
FORCEPROP 1 LAST $LOCATION R4483
J 0
(-2230 1150);
DISPLAY 0.638298 (-2230 1150);
FORCEPROP 1 LASTPIN (-2275 1125) $PN 1
J 0
(-2270 1087);
DISPLAY 0.787234 (-2270 1087);
PAINT MONO (-2270 1087);
FORCEPROP 1 LASTPIN (-2275 925) $PN 2
J 0
(-2270 935);
DISPLAY 0.787234 (-2270 935);
PAINT MONO (-2270 935);
FORCEPROP 1 LAST PATH I206
J 0
(-2225 1200);
DISPLAY 0.978723 (-2225 1200);
PAINT WHITE (-2225 1200);
DISPLAY INVISIBLE (-2225 1200);
FORCEPROP 1 LAST PACK_TYPE 0402LF
J 0
(-2225 850);
DISPLAY 0.510638 (-2225 850);
DISPLAY INVISIBLE (-2225 850);
FORCEPROP 1 LAST TOLERANCE 1%
J 0
(-2230 1050);
DISPLAY 0.510638 (-2230 1050);
DISPLAY INVISIBLE (-2230 1050);
FORCEPROP 1 LAST WATTAGE 1/16W
J 0
(-2235 1000);
DISPLAY 0.510638 (-2235 1000);
DISPLAY INVISIBLE (-2235 1000);
FORCEPROP 2 LAST CDS_LIB pure_quanta
J 0
(-2275 1025);
DISPLAY INVISIBLE (-2275 1025);
FORCEPROP 0 LAST CDS_LOCATION R4483
J 0
(-2225 1200);
DISPLAY 1.021277 (-2225 1200);
DISPLAY INVISIBLE (-2225 1200);
FORCEPROP 0 LAST $SEC 1
J 0
(-2225 1200);
DISPLAY 0.680851 (-2225 1200);
PAINT MONO (-2225 1200);
DISPLAY INVISIBLE (-2225 1200);
FORCEPROP 0 LAST CDS_SEC 1
J 0
(-2225 1200);
DISPLAY 1.021277 (-2225 1200);
DISPLAY INVISIBLE (-2225 1200);
FORCEADD UNIVERSAL_GND..1
(-2275 800);
FORCEPROP 3 LASTPIN (-2275 850) SIG_NAME GND\g
J 0
(-2265 860);
DISPLAY 0.659574 (-2265 860);
PAINT MONO (-2265 860);
DISPLAY INVISIBLE (-2265 860);
FORCEPROP 2 LAST CDS_LIB logical_power
J 0
(-2275 800);
DISPLAY INVISIBLE (-2275 800);
FORCEPROP 1 LAST HDL_POWER GND
J 1
(-2250 725);
DISPLAY 0.872340 (-2250 725);
PAINT GREEN (-2250 725);
DISPLAY INVISIBLE (-2250 725);
FORCEPROP 1 LAST PATH I207
J 0
(-2200 800);
DISPLAY 0.872340 (-2200 800);
PAINT AQUA (-2200 800);
DISPLAY INVISIBLE (-2200 800);
FORCEADD Q_RES..2
(-2450 1025);
FORCEPROP 1 LAST PART_NUMBER CS04992FB07
J 0
(-2410 900);
DISPLAY 0.510638 (-2410 900);
DISPLAY INVISIBLE (-2410 900);
FORCEPROP 1 LAST VALUE 49.9
J 0
(-2400 1000);
DISPLAY 0.510638 (-2400 1000);
FORCEPROP 1 LAST MATERIAL EMPTY
J 0
(-2410 950);
DISPLAY 0.510638 (-2410 950);
PAINT RED (-2410 950);
FORCEPROP 1 LAST $LOCATION R4482
J 0
(-2405 1150);
DISPLAY 0.638298 (-2405 1150);
FORCEPROP 1 LASTPIN (-2450 1125) $PN 1
J 0
(-2445 1087);
DISPLAY 0.787234 (-2445 1087);
PAINT MONO (-2445 1087);
FORCEPROP 1 LASTPIN (-2450 925) $PN 2
J 0
(-2445 935);
DISPLAY 0.787234 (-2445 935);
PAINT MONO (-2445 935);
FORCEPROP 1 LAST PATH I208
J 0
(-2400 1200);
DISPLAY 0.978723 (-2400 1200);
PAINT WHITE (-2400 1200);
DISPLAY INVISIBLE (-2400 1200);
FORCEPROP 1 LAST WATTAGE 1/16W
J 0
(-2410 1000);
DISPLAY 0.510638 (-2410 1000);
DISPLAY INVISIBLE (-2410 1000);
FORCEPROP 1 LAST TOLERANCE 1%
J 0
(-2405 1050);
DISPLAY 0.510638 (-2405 1050);
DISPLAY INVISIBLE (-2405 1050);
FORCEPROP 1 LAST PACK_TYPE 0402LF
J 0
(-2400 850);
DISPLAY 0.510638 (-2400 850);
DISPLAY INVISIBLE (-2400 850);
FORCEPROP 2 LAST CDS_LIB pure_quanta
J 0
(-2450 1025);
DISPLAY INVISIBLE (-2450 1025);
FORCEPROP 0 LAST CDS_LOCATION R4482
J 0
(-2400 1200);
DISPLAY 1.021277 (-2400 1200);
DISPLAY INVISIBLE (-2400 1200);
FORCEPROP 0 LAST $SEC 1
J 0
(-2400 1200);
DISPLAY 0.680851 (-2400 1200);
PAINT MONO (-2400 1200);
DISPLAY INVISIBLE (-2400 1200);
FORCEPROP 0 LAST CDS_SEC 1
J 0
(-2400 1200);
DISPLAY 1.021277 (-2400 1200);
DISPLAY INVISIBLE (-2400 1200);
FORCEADD UNIVERSAL_GND..1
(-2450 800);
FORCEPROP 3 LASTPIN (-2450 850) SIG_NAME GND\g
J 0
(-2440 860);
DISPLAY 0.659574 (-2440 860);
PAINT MONO (-2440 860);
DISPLAY INVISIBLE (-2440 860);
FORCEPROP 2 LAST CDS_LIB logical_power
J 0
(-2450 800);
DISPLAY INVISIBLE (-2450 800);
FORCEPROP 1 LAST HDL_POWER GND
J 1
(-2425 725);
DISPLAY 0.872340 (-2425 725);
PAINT GREEN (-2425 725);
DISPLAY INVISIBLE (-2425 725);
FORCEPROP 1 LAST PATH I209
J 0
(-2375 800);
DISPLAY 0.872340 (-2375 800);
PAINT AQUA (-2375 800);
DISPLAY INVISIBLE (-2375 800);
FORCEADD Q_CAP..1
(3475 4375);
FORCEPROP 1 LAST PART_NUMBER CH01806JB07
J 0
(3525 4225);
DISPLAY 0.510638 (3525 4225);
DISPLAY INVISIBLE (3525 4225);
FORCEPROP 1 LAST TOLERANCE 5%
J 0
(3525 4325);
DISPLAY 0.510638 (3525 4325);
FORCEPROP 1 LAST PACK_TYPE 0402
J 0
(3525 4175);
DISPLAY 0.510638 (3525 4175);
FORCEPROP 1 LAST MATERIAL C0G
J 0
(3525 4275);
DISPLAY 0.510638 (3525 4275);
FORCEPROP 1 LAST VOLTAGE 50V
J 0
(3525 4375);
DISPLAY 0.510638 (3525 4375);
FORCEPROP 1 LAST VALUE 18PF
J 0
(3525 4425);
DISPLAY 0.510638 (3525 4425);
FORCEPROP 0 LAST ROOM USB1_BOM1
J 0
(3525 4575);
DISPLAY 0.638298 (3525 4575);
FORCEPROP 1 LAST LOCATION C2029
J 0
(3525 4475);
DISPLAY 0.638298 (3525 4475);
FORCEPROP 1 LASTPIN (3475 4475) $PN 1
J 0
(3485 4455);
DISPLAY 0.787234 (3485 4455);
PAINT MONO (3485 4455);
FORCEPROP 1 LASTPIN (3475 4275) $PN 2
J 0
(3485 4255);
DISPLAY 0.787234 (3485 4255);
PAINT MONO (3485 4255);
FORCEPROP 1 LAST PATH I210
J 0
(3525 4525);
DISPLAY 0.978723 (3525 4525);
PAINT WHITE (3525 4525);
DISPLAY INVISIBLE (3525 4525);
FORCEPROP 2 LAST CDS_LIB pure_quanta
J 0
(3475 4375);
DISPLAY INVISIBLE (3475 4375);
FORCEPROP 0 LAST $SEC 1
J 0
(3525 4625);
DISPLAY 0.680851 (3525 4625);
PAINT MONO (3525 4625);
DISPLAY INVISIBLE (3525 4625);
FORCEPROP 0 LAST CDS_SEC 1
J 0
(3525 4625);
DISPLAY 1.021277 (3525 4625);
DISPLAY INVISIBLE (3525 4625);
FORCEADD Q_CAP..1
(4475 4375);
FORCEPROP 1 LAST PART_NUMBER CH01806JB07
J 0
(4525 4225);
DISPLAY 0.510638 (4525 4225);
DISPLAY INVISIBLE (4525 4225);
FORCEPROP 1 LAST MATERIAL C0G
J 0
(4525 4275);
DISPLAY 0.510638 (4525 4275);
FORCEPROP 1 LAST PACK_TYPE 0402
J 0
(4525 4175);
DISPLAY 0.510638 (4525 4175);
FORCEPROP 1 LAST VOLTAGE 50V
J 0
(4525 4375);
DISPLAY 0.510638 (4525 4375);
FORCEPROP 0 LAST ROOM USB1_BOM1
J 0
(4525 4550);
DISPLAY 0.638298 (4525 4550);
FORCEPROP 1 LAST VALUE 18PF
J 0
(4525 4425);
DISPLAY 0.510638 (4525 4425);
FORCEPROP 1 LAST TOLERANCE 5%
J 0
(4525 4325);
DISPLAY 0.510638 (4525 4325);
FORCEPROP 1 LAST LOCATION C2030
J 0
(4525 4475);
DISPLAY 0.638298 (4525 4475);
FORCEPROP 1 LASTPIN (4475 4475) $PN 1
J 0
(4485 4455);
DISPLAY 0.787234 (4485 4455);
PAINT MONO (4485 4455);
FORCEPROP 1 LASTPIN (4475 4275) $PN 2
J 0
(4485 4255);
DISPLAY 0.787234 (4485 4255);
PAINT MONO (4485 4255);
FORCEPROP 1 LAST PATH I211
J 0
(4525 4525);
DISPLAY 0.978723 (4525 4525);
PAINT WHITE (4525 4525);
DISPLAY INVISIBLE (4525 4525);
FORCEPROP 2 LAST CDS_LIB pure_quanta
J 0
(4475 4375);
DISPLAY INVISIBLE (4475 4375);
FORCEPROP 0 LAST $SEC 1
J 0
(4525 4600);
DISPLAY 0.680851 (4525 4600);
PAINT MONO (4525 4600);
DISPLAY INVISIBLE (4525 4600);
FORCEPROP 0 LAST CDS_SEC 1
J 0
(4525 4600);
DISPLAY 1.021277 (4525 4600);
DISPLAY INVISIBLE (4525 4600);
FORCEADD OFFPAGE..3
R 2
(-3550 175);
PAINT AQUA (-3550 175);
FORCEPROP 2 LAST $XR0 152 
J 0
(-3860 175);
DISPLAY 0.638298 (-3860 175);
PAINT MONO (-3860 175);
FORCEPROP 2 LAST PATH I76
J 0
(-3825 225);
DISPLAY 1.021277 (-3825 225);
DISPLAY INVISIBLE (-3825 225);
FORCEPROP 1 LAST COMMENT_BODY TRUE
J 2
(-3500 75);
DISPLAY 0.872340 (-3500 75);
PAINT GREEN (-3500 75);
DISPLAY INVISIBLE (-3500 75);
FORCEPROP 1 LAST OFFPAGE TRUE
J 2
(-3875 50);
DISPLAY 0.872340 (-3875 50);
PAINT AQUA (-3875 50);
DISPLAY INVISIBLE (-3875 50);
FORCEPROP 2 LAST CDS_LIB standard
J 2
(-3550 175);
DISPLAY INVISIBLE (-3550 175);
FORCEADD OFFPAGE..3
R 2
(-3550 225);
PAINT AQUA (-3550 225);
FORCEPROP 2 LAST $XR0 152 
J 0
(-3860 225);
DISPLAY 0.638298 (-3860 225);
PAINT MONO (-3860 225);
FORCEPROP 2 LAST PATH I77
J 0
(-3825 275);
DISPLAY 1.021277 (-3825 275);
DISPLAY INVISIBLE (-3825 275);
FORCEPROP 1 LAST COMMENT_BODY TRUE
J 2
(-3500 125);
DISPLAY 0.872340 (-3500 125);
PAINT GREEN (-3500 125);
DISPLAY INVISIBLE (-3500 125);
FORCEPROP 1 LAST OFFPAGE TRUE
J 2
(-3875 100);
DISPLAY 0.872340 (-3875 100);
PAINT AQUA (-3875 100);
DISPLAY INVISIBLE (-3875 100);
FORCEPROP 2 LAST CDS_LIB standard
J 2
(-3550 225);
DISPLAY INVISIBLE (-3550 225);
FORCEADD Q_RES..1
(-2175 175);
FORCEPROP 1 LAST PART_NUMBER CS00002JB13
J 0
(-2450 50);
DISPLAY 0.723404 (-2450 50);
PAINT WHITE (-2450 50);
DISPLAY INVISIBLE (-2450 50);
FORCEPROP 1 LAST VALUE 0
J 2
(-2025 175);
DISPLAY 0.723404 (-2025 175);
FORCEPROP 0 LAST ROOM USB1_BOM1
J 0
(-2800 125);
DISPLAY 0.808511 (-2800 125);
FORCEPROP 1 LAST PACK_TYPE 0402LF
J 0
(-2675 175);
DISPLAY 0.723404 (-2675 175);
FORCEPROP 1 LAST MATERIAL CHIP
J 0
(-2850 175);
DISPLAY 0.723404 (-2850 175);
FORCEPROP 1 LAST $LOCATION R2787
J 0
(-2400 175);
DISPLAY 0.723404 (-2400 175);
FORCEPROP 1 LASTPIN (-2275 175) $PN 1
J 0
(-2263 187);
DISPLAY 0.787234 (-2263 187);
PAINT MONO (-2263 187);
FORCEPROP 1 LASTPIN (-2075 175) $PN 2
J 0
(-2113 187);
DISPLAY 0.787234 (-2113 187);
PAINT MONO (-2113 187);
FORCEPROP 1 LAST PATH I78
J 0
(-2225 325);
DISPLAY 0.978723 (-2225 325);
PAINT WHITE (-2225 325);
DISPLAY INVISIBLE (-2225 325);
FORCEPROP 2 LAST CDS_LIB pure_quanta
J 0
(-2175 175);
DISPLAY INVISIBLE (-2175 175);
FORCEPROP 1 LAST WATTAGE 1/16W
J 2
(-2100 100);
DISPLAY 0.723404 (-2100 100);
PAINT SKYBLUE (-2100 100);
DISPLAY INVISIBLE (-2100 100);
FORCEPROP 1 LAST TOLERANCE 5%
J 0
(-2375 100);
DISPLAY 0.723404 (-2375 100);
PAINT SKYBLUE (-2375 100);
DISPLAY INVISIBLE (-2375 100);
FORCEPROP 2 LAST CDS_LOCATION R2787
J 0
(-2225 375);
DISPLAY 1.021277 (-2225 375);
DISPLAY INVISIBLE (-2225 375);
FORCEPROP 2 LAST $SEC 1
J 0
(-2225 375);
DISPLAY 0.680851 (-2225 375);
PAINT MONO (-2225 375);
DISPLAY INVISIBLE (-2225 375);
FORCEPROP 2 LAST CDS_SEC 1
J 0
(-2225 375);
DISPLAY 1.021277 (-2225 375);
DISPLAY INVISIBLE (-2225 375);
FORCEADD Q_RES..1
(-2175 225);
FORCEPROP 1 LAST PART_NUMBER CS00002JB13
J 0
(-2450 100);
DISPLAY 0.723404 (-2450 100);
PAINT WHITE (-2450 100);
DISPLAY INVISIBLE (-2450 100);
FORCEPROP 0 LAST ROOM USB1_BOM1
J 0
(-2800 275);
DISPLAY 0.808511 (-2800 275);
FORCEPROP 1 LAST PACK_TYPE 0402LF
J 0
(-2675 225);
DISPLAY 0.723404 (-2675 225);
FORCEPROP 1 LAST VALUE 0
J 2
(-2025 225);
DISPLAY 0.723404 (-2025 225);
FORCEPROP 1 LAST MATERIAL CHIP
J 0
(-2850 225);
DISPLAY 0.723404 (-2850 225);
FORCEPROP 1 LAST $LOCATION R2786
J 0
(-2400 225);
DISPLAY 0.723404 (-2400 225);
FORCEPROP 1 LASTPIN (-2275 225) $PN 1
J 0
(-2263 237);
DISPLAY 0.787234 (-2263 237);
PAINT MONO (-2263 237);
FORCEPROP 1 LASTPIN (-2075 225) $PN 2
J 0
(-2113 237);
DISPLAY 0.787234 (-2113 237);
PAINT MONO (-2113 237);
FORCEPROP 1 LAST PATH I79
J 0
(-2225 375);
DISPLAY 0.978723 (-2225 375);
PAINT WHITE (-2225 375);
DISPLAY INVISIBLE (-2225 375);
FORCEPROP 2 LAST CDS_LIB pure_quanta
J 0
(-2175 225);
DISPLAY INVISIBLE (-2175 225);
FORCEPROP 1 LAST WATTAGE 1/16W
J 2
(-2100 150);
DISPLAY 0.723404 (-2100 150);
PAINT SKYBLUE (-2100 150);
DISPLAY INVISIBLE (-2100 150);
FORCEPROP 1 LAST TOLERANCE 5%
J 0
(-2375 150);
DISPLAY 0.723404 (-2375 150);
PAINT SKYBLUE (-2375 150);
DISPLAY INVISIBLE (-2375 150);
FORCEPROP 2 LAST CDS_LOCATION R2786
J 0
(-2225 425);
DISPLAY 1.021277 (-2225 425);
DISPLAY INVISIBLE (-2225 425);
FORCEPROP 2 LAST $SEC 1
J 0
(-2225 425);
DISPLAY 0.680851 (-2225 425);
PAINT MONO (-2225 425);
DISPLAY INVISIBLE (-2225 425);
FORCEPROP 2 LAST CDS_SEC 1
J 0
(-2225 425);
DISPLAY 1.021277 (-2225 425);
DISPLAY INVISIBLE (-2225 425);
FORCEADD UNIVERSAL_GND..1
(-1150 -450);
FORCEPROP 3 LASTPIN (-1150 -400) SIG_NAME GND\g
J 0
(-1140 -390);
DISPLAY 0.659574 (-1140 -390);
PAINT MONO (-1140 -390);
DISPLAY INVISIBLE (-1140 -390);
FORCEPROP 1 LAST PATH I80
J 0
(-1075 -450);
DISPLAY 0.872340 (-1075 -450);
PAINT AQUA (-1075 -450);
DISPLAY INVISIBLE (-1075 -450);
FORCEPROP 1 LAST HDL_POWER GND
J 1
(-1125 -525);
DISPLAY 0.872340 (-1125 -525);
PAINT GREEN (-1125 -525);
DISPLAY INVISIBLE (-1125 -525);
FORCEPROP 2 LAST CDS_LIB logical_power
J 0
(-1150 -450);
DISPLAY INVISIBLE (-1150 -450);
FORCEADD Q_CAP..1
(-1150 -225);
FORCEPROP 1 LAST PART_NUMBER CH4104K1B00
J 0
(-1100 -375);
DISPLAY 0.723404 (-1100 -375);
PAINT WHITE (-1100 -375);
DISPLAY INVISIBLE (-1100 -375);
FORCEPROP 1 LAST MATERIAL EMPTY
J 0
(-1100 -325);
DISPLAY 0.723404 (-1100 -325);
PAINT SKYBLUE (-1100 -325);
FORCEPROP 1 LAST TOLERANCE 10%
J 0
(-1100 -275);
DISPLAY 0.723404 (-1100 -275);
PAINT SKYBLUE (-1100 -275);
FORCEPROP 1 LAST VOLTAGE 25V
J 0
(-1100 -225);
DISPLAY 0.723404 (-1100 -225);
PAINT SKYBLUE (-1100 -225);
FORCEPROP 0 LAST ROOM USB1_BOM2
J 0
(-1100 -475);
DISPLAY 0.808511 (-1100 -475);
FORCEPROP 1 LAST VALUE 0.1UF
J 0
(-1100 -175);
DISPLAY 0.723404 (-1100 -175);
PAINT SKYBLUE (-1100 -175);
FORCEPROP 1 LAST PACK_TYPE 0402
J 0
(-1100 -425);
DISPLAY 0.723404 (-1100 -425);
PAINT SKYBLUE (-1100 -425);
FORCEPROP 1 LAST $LOCATION C5232
J 0
(-1100 -125);
DISPLAY 0.723404 (-1100 -125);
PAINT AQUA (-1100 -125);
FORCEPROP 1 LASTPIN (-1150 -125) $PN 1
J 0
(-1140 -145);
DISPLAY 0.723404 (-1140 -145);
PAINT MONO (-1140 -145);
FORCEPROP 1 LASTPIN (-1150 -325) $PN 2
J 0
(-1140 -345);
DISPLAY 0.723404 (-1140 -345);
PAINT MONO (-1140 -345);
FORCEPROP 1 LAST PATH I81
J 0
(-1100 -75);
DISPLAY 0.978723 (-1100 -75);
PAINT WHITE (-1100 -75);
DISPLAY INVISIBLE (-1100 -75);
FORCEPROP 2 LAST CDS_LIB pure_quanta
J 0
(-1150 -225);
DISPLAY INVISIBLE (-1150 -225);
FORCEPROP 2 LAST CDS_LOCATION C5232
J 0
(-1100 -125);
DISPLAY 0.723404 (-1100 -125);
PAINT AQUA (-1100 -125);
DISPLAY INVISIBLE (-1100 -125);
FORCEPROP 2 LAST $SEC 1
J 0
(-1100 -25);
DISPLAY 0.680851 (-1100 -25);
PAINT MONO (-1100 -25);
DISPLAY INVISIBLE (-1100 -25);
FORCEPROP 0 LAST CDS_SEC 1
J 0
(-1100 -75);
DISPLAY INVISIBLE (-1100 -75);
FORCEADD UNIVERSAL_GND..1
(-675 -450);
FORCEPROP 3 LASTPIN (-675 -400) SIG_NAME GND\g
J 0
(-665 -390);
DISPLAY 0.659574 (-665 -390);
PAINT MONO (-665 -390);
DISPLAY INVISIBLE (-665 -390);
FORCEPROP 1 LAST PATH I82
J 0
(-600 -450);
DISPLAY 0.872340 (-600 -450);
PAINT AQUA (-600 -450);
DISPLAY INVISIBLE (-600 -450);
FORCEPROP 1 LAST HDL_POWER GND
J 1
(-650 -525);
DISPLAY 0.872340 (-650 -525);
PAINT GREEN (-650 -525);
DISPLAY INVISIBLE (-650 -525);
FORCEPROP 2 LAST CDS_LIB logical_power
J 0
(-675 -450);
DISPLAY INVISIBLE (-675 -450);
FORCEADD Q_RES..2
(-675 -250);
FORCEPROP 1 LAST PART_NUMBER CS23902JB04
J 0
(-635 -375);
DISPLAY 0.723404 (-635 -375);
PAINT WHITE (-635 -375);
DISPLAY INVISIBLE (-635 -375);
FORCEPROP 1 LAST MATERIAL EMPTY
J 0
(-635 -325);
DISPLAY 0.723404 (-635 -325);
PAINT SKYBLUE (-635 -325);
FORCEPROP 1 LAST VALUE 3.9K
J 0
(-630 -175);
DISPLAY 0.723404 (-630 -175);
PAINT SKYBLUE (-630 -175);
FORCEPROP 1 LAST WATTAGE 1/16W
J 0
(-635 -275);
DISPLAY 0.723404 (-635 -275);
PAINT SKYBLUE (-635 -275);
FORCEPROP 1 LAST TOLERANCE 5%
J 0
(-630 -225);
DISPLAY 0.723404 (-630 -225);
PAINT SKYBLUE (-630 -225);
FORCEPROP 1 LAST PACK_TYPE 0402LF
J 0
(-635 -425);
DISPLAY 0.723404 (-635 -425);
PAINT SKYBLUE (-635 -425);
FORCEPROP 0 LAST ROOM USB1_BOM2
J 0
(-625 -475);
DISPLAY 0.808511 (-625 -475);
FORCEPROP 1 LAST $LOCATION R5238
J 0
(-630 -125);
DISPLAY 0.723404 (-630 -125);
PAINT AQUA (-630 -125);
FORCEPROP 1 LAST PATH I83
J 0
(-625 -75);
DISPLAY 0.978723 (-625 -75);
PAINT WHITE (-625 -75);
DISPLAY INVISIBLE (-625 -75);
FORCEPROP 2 LAST CDS_LIB pure_quanta
J 0
(-675 -250);
DISPLAY INVISIBLE (-675 -250);
FORCEPROP 0 LAST CDS_LOCATION R5238
J 0
(-625 -75);
DISPLAY INVISIBLE (-625 -75);
FORCEPROP 0 LAST $SEC 1
J 0
(-625 -75);
DISPLAY INVISIBLE (-625 -75);
FORCEPROP 0 LAST CDS_SEC 1
J 0
(-625 -75);
DISPLAY INVISIBLE (-625 -75);
FORCEPROP 1 LASTPIN (-675 -150) $PN 1
J 0
(-670 -188);
DISPLAY 0.787234 (-670 -188);
PAINT MONO (-670 -188);
DISPLAY INVISIBLE (-670 -188);
FORCEPROP 1 LASTPIN (-675 -350) $PN 2
J 0
(-670 -340);
DISPLAY 0.787234 (-670 -340);
PAINT MONO (-670 -340);
DISPLAY INVISIBLE (-670 -340);
FORCEADD TUSB211IRWBR..1
(-125 100);
FORCEPROP 1 LAST PART_NUMBER AL000211007
J 0
(-352 348);
DISPLAY 0.723404 (-352 348);
PAINT WHITE (-352 348);
DISPLAY INVISIBLE (-352 348);
FORCEPROP 2 LAST PART_TYPE SMLF
J 0
(-350 525);
DISPLAY 1.021277 (-350 525);
FORCEPROP 2 LAST VALUE TUSB211IRWBR
J 0
(-350 475);
DISPLAY 0.723404 (-350 475);
PAINT SKYBLUE (-350 475);
FORCEPROP 0 LAST ROOM USB1_BOM2
J 0
(-350 600);
DISPLAY 1.021277 (-350 600);
FORCEPROP 1 LAST MATERIAL EMPTY
J 0
(-352 279);
DISPLAY 0.723404 (-352 279);
PAINT SKYBLUE (-352 279);
FORCEPROP 1 LAST $LOCATION U5201
J 0
(-352 424);
DISPLAY 0.723404 (-352 424);
PAINT AQUA (-352 424);
FORCEPROP 0 LASTPIN (-500 75) $PN 4
J 2
(-510 85);
DISPLAY 0.808511 (-510 85);
FORCEPROP 0 LASTPIN (-500 175) $PN 1
J 2
(-510 185);
DISPLAY 0.808511 (-510 185);
FORCEPROP 0 LASTPIN (-500 225) $PN 2
J 2
(-510 235);
DISPLAY 0.808511 (-510 235);
FORCEPROP 0 LASTPIN (250 175) $PN 8
J 0
(260 185);
DISPLAY 0.808511 (260 185);
FORCEPROP 0 LASTPIN (250 225) $PN 7
J 0
(260 235);
DISPLAY 0.808511 (260 235);
FORCEPROP 0 LASTPIN (250 -25) $PN 9
J 0
(260 -15);
DISPLAY 0.808511 (260 -15);
FORCEPROP 0 LASTPIN (-500 -25) $PN 6
J 2
(-510 -15);
DISPLAY 0.808511 (-510 -15);
FORCEPROP 0 LASTPIN (250 25) $PN 10
J 0
(260 35);
DISPLAY 0.808511 (260 35);
FORCEPROP 0 LASTPIN (-500 25) $PN 5
J 2
(-510 35);
DISPLAY 0.808511 (-510 35);
FORCEPROP 0 LASTPIN (-500 125) $PN 3
J 2
(-510 135);
DISPLAY 0.808511 (-510 135);
FORCEPROP 0 LASTPIN (250 125) $PN 12
J 0
(260 135);
DISPLAY 0.808511 (260 135);
FORCEPROP 0 LASTPIN (250 75) $PN 11
J 0
(260 85);
DISPLAY 0.808511 (260 85);
FORCEPROP 1 LAST PATH I84
J 0
(100 -75);
DISPLAY 0.723404 (100 -75);
PAINT GREEN (100 -75);
DISPLAY INVISIBLE (100 -75);
FORCEPROP 2 LAST CDS_LIB pure_quanta
J 0
(-125 100);
DISPLAY INVISIBLE (-125 100);
FORCEPROP 1 LAST CDS_LMAN_SYM_OUTLINE -225,175,225,-175
J 0
(-125 100);
DISPLAY 0.468085 (-125 100);
PAINT GREEN (-125 100);
DISPLAY INVISIBLE (-125 100);
FORCEPROP 1 LAST NEEDS_NO_SIZE TRUE
J 0
(100 -18);
DISPLAY 0.723404 (100 -18);
PAINT GREEN (100 -18);
DISPLAY INVISIBLE (100 -18);
FORCEPROP 0 LAST CDS_LOCATION U5201
J 0
(-350 575);
DISPLAY INVISIBLE (-350 575);
FORCEPROP 0 LAST $SEC 1
J 0
(-350 575);
DISPLAY INVISIBLE (-350 575);
FORCEPROP 0 LAST CDS_SEC 1
J 0
(-350 575);
DISPLAY INVISIBLE (-350 575);
FORCEADD UNIVERSAL_GND..1
(1475 -425);
FORCEPROP 3 LASTPIN (1475 -375) SIG_NAME GND\g
J 0
(1485 -365);
DISPLAY 0.659574 (1485 -365);
PAINT MONO (1485 -365);
DISPLAY INVISIBLE (1485 -365);
FORCEPROP 1 LAST PATH I85
J 0
(1550 -425);
DISPLAY 0.872340 (1550 -425);
PAINT AQUA (1550 -425);
DISPLAY INVISIBLE (1550 -425);
FORCEPROP 1 LAST HDL_POWER GND
J 1
(1500 -500);
DISPLAY 0.872340 (1500 -500);
PAINT GREEN (1500 -500);
DISPLAY INVISIBLE (1500 -500);
FORCEPROP 2 LAST CDS_LIB logical_power
J 0
(1475 -425);
DISPLAY INVISIBLE (1475 -425);
FORCEADD UNIVERSAL_GND..1
(1375 -150);
FORCEPROP 3 LASTPIN (1375 -100) SIG_NAME GND\g
J 0
(1385 -90);
DISPLAY 0.659574 (1385 -90);
PAINT MONO (1385 -90);
DISPLAY INVISIBLE (1385 -90);
FORCEPROP 1 LAST PATH I86
J 0
(1450 -150);
DISPLAY 0.872340 (1450 -150);
PAINT AQUA (1450 -150);
DISPLAY INVISIBLE (1450 -150);
FORCEPROP 1 LAST HDL_POWER GND
J 1
(1400 -225);
DISPLAY 0.872340 (1400 -225);
PAINT GREEN (1400 -225);
DISPLAY INVISIBLE (1400 -225);
FORCEPROP 2 LAST CDS_LIB logical_power
J 0
(1375 -150);
DISPLAY INVISIBLE (1375 -150);
FORCEADD Q_CAP..1
(1475 -200);
FORCEPROP 1 LAST PART_NUMBER CH4104K1B00
J 0
(1525 -350);
DISPLAY 0.723404 (1525 -350);
DISPLAY INVISIBLE (1525 -350);
FORCEPROP 1 LAST MATERIAL EMPTY
J 0
(1525 -300);
DISPLAY 0.723404 (1525 -300);
FORCEPROP 1 LAST TOLERANCE 10%
J 0
(1525 -250);
DISPLAY 0.723404 (1525 -250);
FORCEPROP 1 LAST VOLTAGE 25V
J 0
(1525 -200);
DISPLAY 0.723404 (1525 -200);
FORCEPROP 1 LAST VALUE 0.1UF
J 0
(1525 -150);
DISPLAY 0.723404 (1525 -150);
FORCEPROP 0 LAST ROOM USB1_BOM2
J 0
(1525 -50);
DISPLAY 0.808511 (1525 -50);
FORCEPROP 1 LAST PACK_TYPE 0402
J 0
(1525 -400);
DISPLAY 0.723404 (1525 -400);
FORCEPROP 1 LAST $LOCATION C5236
J 0
(1525 -100);
DISPLAY 0.723404 (1525 -100);
FORCEPROP 1 LASTPIN (1475 -100) $PN 1
J 0
(1485 -120);
DISPLAY 0.723404 (1485 -120);
PAINT MONO (1485 -120);
FORCEPROP 1 LASTPIN (1475 -300) $PN 2
J 0
(1485 -320);
DISPLAY 0.723404 (1485 -320);
PAINT MONO (1485 -320);
FORCEPROP 1 LAST PATH I87
J 0
(1525 -50);
DISPLAY 0.978723 (1525 -50);
PAINT WHITE (1525 -50);
DISPLAY INVISIBLE (1525 -50);
FORCEPROP 2 LAST CDS_LIB pure_quanta
J 0
(1475 -200);
DISPLAY INVISIBLE (1475 -200);
FORCEPROP 2 LAST CDS_LOCATION C5236
J 0
(1525 -100);
DISPLAY 0.723404 (1525 -100);
PAINT AQUA (1525 -100);
DISPLAY INVISIBLE (1525 -100);
FORCEPROP 2 LAST $SEC 1
J 0
(1525 0);
DISPLAY 0.680851 (1525 0);
PAINT MONO (1525 0);
DISPLAY INVISIBLE (1525 0);
FORCEPROP 0 LAST CDS_SEC 1
J 0
(1525 -50);
DISPLAY INVISIBLE (1525 -50);
FORCEADD Q_CAP..1
(75 750);
FORCEPROP 1 LAST PART_NUMBER CH5104KEB02
J 0
(125 600);
DISPLAY 0.723404 (125 600);
DISPLAY INVISIBLE (125 600);
FORCEPROP 1 LAST VALUE 1UF
J 0
(125 800);
DISPLAY 0.723404 (125 800);
FORCEPROP 1 LAST VOLTAGE 25V
J 0
(125 750);
DISPLAY 0.723404 (125 750);
FORCEPROP 1 LAST PACK_TYPE C0402
J 0
(125 550);
DISPLAY 0.723404 (125 550);
FORCEPROP 0 LAST ROOM USB1_BOM2
J 0
(125 900);
DISPLAY 0.808511 (125 900);
FORCEPROP 1 LAST TOLERANCE 10%
J 0
(125 700);
DISPLAY 0.723404 (125 700);
FORCEPROP 1 LAST MATERIAL EMPTY
J 0
(125 650);
DISPLAY 0.723404 (125 650);
FORCEPROP 1 LAST $LOCATION C5229
J 0
(125 850);
DISPLAY 0.723404 (125 850);
FORCEPROP 1 LASTPIN (75 850) $PN 1
J 0
(85 830);
DISPLAY 0.723404 (85 830);
PAINT MONO (85 830);
FORCEPROP 1 LASTPIN (75 650) $PN 2
J 0
(85 630);
DISPLAY 0.723404 (85 630);
PAINT MONO (85 630);
FORCEPROP 1 LAST PATH I88
J 0
(125 900);
DISPLAY 0.978723 (125 900);
PAINT WHITE (125 900);
DISPLAY INVISIBLE (125 900);
FORCEPROP 2 LAST CDS_LIB pure_quanta
J 0
(75 750);
DISPLAY INVISIBLE (75 750);
FORCEPROP 2 LAST CDS_LOCATION C5229
J 0
(125 850);
DISPLAY 0.723404 (125 850);
PAINT AQUA (125 850);
DISPLAY INVISIBLE (125 850);
FORCEPROP 2 LAST $SEC 1
J 0
(125 950);
DISPLAY 0.680851 (125 950);
PAINT MONO (125 950);
DISPLAY INVISIBLE (125 950);
FORCEPROP 0 LAST CDS_SEC 1
J 0
(125 950);
DISPLAY 0.680851 (125 950);
PAINT MONO (125 950);
DISPLAY INVISIBLE (125 950);
FORCEADD UNIVERSAL_GND..1
(575 375);
FORCEPROP 3 LASTPIN (575 425) SIG_NAME GND\g
J 0
(585 435);
DISPLAY 0.659574 (585 435);
PAINT MONO (585 435);
DISPLAY INVISIBLE (585 435);
FORCEPROP 1 LAST PATH I89
J 0
(650 375);
DISPLAY 0.872340 (650 375);
PAINT AQUA (650 375);
DISPLAY INVISIBLE (650 375);
FORCEPROP 1 LAST HDL_POWER GND
J 1
(600 300);
DISPLAY 0.872340 (600 300);
PAINT GREEN (600 300);
DISPLAY INVISIBLE (600 300);
FORCEPROP 2 LAST CDS_LIB logical_power
J 0
(575 375);
DISPLAY INVISIBLE (575 375);
FORCEADD Q_RES..1
(1375 175);
FORCEPROP 1 LAST PART_NUMBER CS00002JB13
J 0
(1100 50);
DISPLAY 0.723404 (1100 50);
PAINT WHITE (1100 50);
DISPLAY INVISIBLE (1100 50);
FORCEPROP 1 LAST PACK_TYPE 0402LF
J 0
(1800 175);
DISPLAY 0.723404 (1800 175);
FORCEPROP 1 LAST VALUE 0
J 2
(1525 175);
DISPLAY 0.723404 (1525 175);
FORCEPROP 1 LAST MATERIAL CHIP
J 0
(1625 175);
DISPLAY 0.723404 (1625 175);
FORCEPROP 1 LAST $LOCATION R5236
J 0
(1125 175);
DISPLAY 0.723404 (1125 175);
FORCEPROP 1 LASTPIN (1275 175) $PN 1
J 0
(1287 187);
DISPLAY 0.723404 (1287 187);
PAINT MONO (1287 187);
FORCEPROP 1 LASTPIN (1475 175) $PN 2
J 0
(1437 187);
DISPLAY 0.723404 (1437 187);
PAINT MONO (1437 187);
FORCEPROP 1 LAST PATH I90
J 0
(1325 325);
DISPLAY 0.978723 (1325 325);
PAINT WHITE (1325 325);
DISPLAY INVISIBLE (1325 325);
FORCEPROP 2 LAST CDS_LIB pure_quanta
J 0
(1375 175);
DISPLAY INVISIBLE (1375 175);
FORCEPROP 1 LAST TOLERANCE 5%
J 0
(1175 100);
DISPLAY 0.723404 (1175 100);
PAINT SKYBLUE (1175 100);
DISPLAY INVISIBLE (1175 100);
FORCEPROP 1 LAST WATTAGE 1/16W
J 2
(1450 100);
DISPLAY 0.723404 (1450 100);
PAINT SKYBLUE (1450 100);
DISPLAY INVISIBLE (1450 100);
FORCEPROP 2 LAST CDS_LOCATION R5236
J 0
(1125 175);
DISPLAY 0.723404 (1125 175);
PAINT AQUA (1125 175);
DISPLAY INVISIBLE (1125 175);
FORCEPROP 2 LAST $SEC 1
J 0
(1325 375);
DISPLAY 0.680851 (1325 375);
PAINT MONO (1325 375);
DISPLAY INVISIBLE (1325 375);
FORCEPROP 2 LAST CDS_SEC 1
J 0
(1325 375);
DISPLAY 1.021277 (1325 375);
DISPLAY INVISIBLE (1325 375);
FORCEADD Q_RES..1
(1375 225);
FORCEPROP 1 LAST PART_NUMBER CS00002JB13
J 0
(1100 100);
DISPLAY 0.723404 (1100 100);
PAINT WHITE (1100 100);
DISPLAY INVISIBLE (1100 100);
FORCEPROP 1 LAST PACK_TYPE 0402LF
J 0
(1800 225);
DISPLAY 0.723404 (1800 225);
FORCEPROP 1 LAST MATERIAL CHIP
J 0
(1625 225);
DISPLAY 0.723404 (1625 225);
FORCEPROP 1 LAST VALUE 0
J 2
(1525 225);
DISPLAY 0.723404 (1525 225);
FORCEPROP 1 LAST $LOCATION R5234
J 0
(1125 225);
DISPLAY 0.723404 (1125 225);
FORCEPROP 1 LASTPIN (1275 225) $PN 1
J 0
(1287 237);
DISPLAY 0.723404 (1287 237);
PAINT MONO (1287 237);
FORCEPROP 1 LASTPIN (1475 225) $PN 2
J 0
(1437 237);
DISPLAY 0.723404 (1437 237);
PAINT MONO (1437 237);
FORCEPROP 1 LAST PATH I91
J 0
(1325 375);
DISPLAY 0.978723 (1325 375);
PAINT WHITE (1325 375);
DISPLAY INVISIBLE (1325 375);
FORCEPROP 2 LAST CDS_LIB pure_quanta
J 0
(1375 225);
DISPLAY INVISIBLE (1375 225);
FORCEPROP 1 LAST TOLERANCE 5%
J 0
(1175 150);
DISPLAY 0.723404 (1175 150);
PAINT SKYBLUE (1175 150);
DISPLAY INVISIBLE (1175 150);
FORCEPROP 1 LAST WATTAGE 1/16W
J 2
(1450 150);
DISPLAY 0.723404 (1450 150);
PAINT SKYBLUE (1450 150);
DISPLAY INVISIBLE (1450 150);
FORCEPROP 2 LAST CDS_LOCATION R5234
J 0
(1125 225);
DISPLAY 0.723404 (1125 225);
PAINT AQUA (1125 225);
DISPLAY INVISIBLE (1125 225);
FORCEPROP 2 LAST $SEC 1
J 0
(1325 425);
DISPLAY 0.680851 (1325 425);
PAINT MONO (1325 425);
DISPLAY INVISIBLE (1325 425);
FORCEPROP 2 LAST CDS_SEC 1
J 0
(1325 425);
DISPLAY 1.021277 (1325 425);
DISPLAY INVISIBLE (1325 425);
FORCEADD Q_CAP..1
(575 725);
FORCEPROP 1 LAST PART_NUMBER CH4104K1B00
J 0
(625 575);
DISPLAY 0.723404 (625 575);
DISPLAY INVISIBLE (625 575);
FORCEPROP 1 LAST MATERIAL EMPTY
J 0
(625 625);
DISPLAY 0.723404 (625 625);
FORCEPROP 0 LAST ROOM USB1_BOM2
J 0
(625 475);
DISPLAY 0.808511 (625 475);
FORCEPROP 1 LAST VALUE 0.1UF
J 0
(625 775);
DISPLAY 0.723404 (625 775);
FORCEPROP 1 LAST VOLTAGE 25V
J 0
(625 725);
DISPLAY 0.723404 (625 725);
FORCEPROP 1 LAST TOLERANCE 10%
J 0
(625 675);
DISPLAY 0.723404 (625 675);
FORCEPROP 1 LAST PACK_TYPE 0402
J 0
(625 525);
DISPLAY 0.723404 (625 525);
FORCEPROP 1 LAST $LOCATION C5234
J 0
(625 825);
DISPLAY 0.723404 (625 825);
FORCEPROP 1 LASTPIN (575 825) $PN 1
J 0
(585 805);
DISPLAY 0.723404 (585 805);
PAINT MONO (585 805);
FORCEPROP 1 LASTPIN (575 625) $PN 2
J 0
(585 605);
DISPLAY 0.723404 (585 605);
PAINT MONO (585 605);
FORCEPROP 1 LAST PATH I92
J 0
(625 875);
DISPLAY 0.978723 (625 875);
PAINT WHITE (625 875);
DISPLAY INVISIBLE (625 875);
FORCEPROP 2 LAST CDS_LIB pure_quanta
J 0
(575 725);
DISPLAY INVISIBLE (575 725);
FORCEPROP 2 LAST CDS_LOCATION C5234
J 0
(625 825);
DISPLAY 0.723404 (625 825);
PAINT AQUA (625 825);
DISPLAY INVISIBLE (625 825);
FORCEPROP 2 LAST $SEC 1
J 0
(625 925);
DISPLAY 0.680851 (625 925);
PAINT MONO (625 925);
DISPLAY INVISIBLE (625 925);
FORCEPROP 0 LAST CDS_SEC 1
J 0
(625 875);
DISPLAY INVISIBLE (625 875);
FORCEADD OFFPAGE..3
(3100 175);
PAINT AQUA (3100 175);
FORCEPROP 2 LAST $XR0 143 
J 0
(3314 175);
DISPLAY 0.638298 (3314 175);
PAINT MONO (3314 175);
FORCEPROP 2 LAST PATH I93
J 0
(3325 225);
DISPLAY 1.021277 (3325 225);
DISPLAY INVISIBLE (3325 225);
FORCEPROP 1 LAST COMMENT_BODY TRUE
J 0
(3050 75);
DISPLAY 0.872340 (3050 75);
PAINT GREEN (3050 75);
DISPLAY INVISIBLE (3050 75);
FORCEPROP 1 LAST OFFPAGE TRUE
J 0
(3425 50);
DISPLAY 0.872340 (3425 50);
PAINT AQUA (3425 50);
DISPLAY INVISIBLE (3425 50);
FORCEPROP 2 LAST CDS_LIB standard
J 0
(3100 175);
DISPLAY INVISIBLE (3100 175);
FORCEADD OFFPAGE..3
(3100 225);
PAINT AQUA (3100 225);
FORCEPROP 2 LAST $XR0 143 
J 0
(3314 225);
DISPLAY 0.638298 (3314 225);
PAINT MONO (3314 225);
FORCEPROP 2 LAST PATH I94
J 0
(3325 275);
DISPLAY 1.021277 (3325 275);
DISPLAY INVISIBLE (3325 275);
FORCEPROP 1 LAST COMMENT_BODY TRUE
J 0
(3050 125);
DISPLAY 0.872340 (3050 125);
PAINT GREEN (3050 125);
DISPLAY INVISIBLE (3050 125);
FORCEPROP 1 LAST OFFPAGE TRUE
J 0
(3425 100);
DISPLAY 0.872340 (3425 100);
PAINT AQUA (3425 100);
DISPLAY INVISIBLE (3425 100);
FORCEPROP 2 LAST CDS_LIB standard
J 0
(3100 225);
DISPLAY INVISIBLE (3100 225);
FORCEADD UNIVERSAL_POWER..1
R 2
(1125 1050);
FORCEPROP 3 LASTPIN (1125 1000) SIG_NAME P3V3_AUX\g
J 0
(1135 1010);
DISPLAY 0.659574 (1135 1010);
PAINT MONO (1135 1010);
DISPLAY INVISIBLE (1135 1010);
FORCEPROP 1 LAST HDL_POWER P3V3_AUX
J 1
(1125 1100);
DISPLAY 0.723404 (1125 1100);
PAINT GREEN (1125 1100);
FORCEPROP 1 LAST PATH I95
J 2
(1075 1075);
DISPLAY 0.872340 (1075 1075);
PAINT AQUA (1075 1075);
DISPLAY INVISIBLE (1075 1075);
FORCEPROP 2 LAST CDS_LIB logical_power
J 0
(1125 1050);
DISPLAY INVISIBLE (1125 1050);
FORCEADD Q_RES..2
(2725 3650);
FORCEPROP 1 LAST PART_NUMBER CS00002JB13
J 0
(2745 3600);
DISPLAY 0.510638 (2745 3600);
DISPLAY INVISIBLE (2745 3600);
FORCEPROP 1 LAST VALUE 0
J 0
(2675 3675);
DISPLAY 0.510638 (2675 3675);
FORCEPROP 1 LAST MATERIAL EMPTY
J 0
(2600 3525);
DISPLAY 0.510638 (2600 3525);
PAINT RED (2600 3525);
FORCEPROP 0 LAST ROOM USB1_BOM2
J 0
(2450 3475);
DISPLAY 0.638298 (2450 3475);
FORCEPROP 1 LAST $LOCATION R2790
J 0
(2625 3725);
DISPLAY 0.510638 (2625 3725);
FORCEPROP 1 LASTPIN (2725 3750) $PN 1
J 0
(2730 3712);
DISPLAY 0.787234 (2730 3712);
PAINT MONO (2730 3712);
FORCEPROP 1 LASTPIN (2725 3550) $PN 2
J 0
(2730 3560);
DISPLAY 0.787234 (2730 3560);
PAINT MONO (2730 3560);
FORCEPROP 1 LAST PATH I96
J 0
(2775 3825);
DISPLAY 0.978723 (2775 3825);
PAINT WHITE (2775 3825);
DISPLAY INVISIBLE (2775 3825);
FORCEPROP 2 LAST CDS_LIB pure_quanta
J 0
(2725 3650);
DISPLAY INVISIBLE (2725 3650);
FORCEPROP 1 LAST PACK_TYPE 0402LF
J 0
(2745 3550);
DISPLAY 0.510638 (2745 3550);
DISPLAY INVISIBLE (2745 3550);
FORCEPROP 1 LAST TOLERANCE 5%
J 0
(2750 3750);
DISPLAY 0.510638 (2750 3750);
DISPLAY INVISIBLE (2750 3750);
FORCEPROP 1 LAST WATTAGE 1/16W
J 0
(2745 3700);
DISPLAY 0.510638 (2745 3700);
DISPLAY INVISIBLE (2745 3700);
FORCEPROP 2 LAST CDS_LOCATION R2790
J 0
(2775 3875);
DISPLAY 1.021277 (2775 3875);
DISPLAY INVISIBLE (2775 3875);
FORCEPROP 2 LAST $SEC 1
J 0
(2775 3875);
DISPLAY 0.680851 (2775 3875);
PAINT MONO (2775 3875);
DISPLAY INVISIBLE (2775 3875);
FORCEPROP 2 LAST CDS_SEC 1
J 0
(2775 3875);
DISPLAY 1.021277 (2775 3875);
DISPLAY INVISIBLE (2775 3875);
FORCEADD Q_RES..2
(2825 3650);
FORCEPROP 1 LAST PART_NUMBER CS00002JB13
J 0
(2875 3475);
DISPLAY 0.510638 (2875 3475);
DISPLAY INVISIBLE (2875 3475);
FORCEPROP 1 LAST MATERIAL EMPTY
J 0
(2875 3525);
DISPLAY 0.510638 (2875 3525);
PAINT RED (2875 3525);
FORCEPROP 1 LAST PACK_TYPE 0402LF
J 0
(2875 3425);
DISPLAY 0.510638 (2875 3425);
FORCEPROP 1 LAST WATTAGE 1/16W
J 0
(2875 3575);
DISPLAY 0.510638 (2875 3575);
FORCEPROP 1 LAST TOLERANCE 5%
J 0
(2880 3625);
DISPLAY 0.510638 (2880 3625);
FORCEPROP 1 LAST VALUE 0
J 0
(2880 3675);
DISPLAY 0.510638 (2880 3675);
FORCEPROP 0 LAST ROOM USB1_BOM2
J 0
(2875 3375);
DISPLAY 0.638298 (2875 3375);
FORCEPROP 1 LAST $LOCATION R2791
J 0
(2880 3725);
DISPLAY 0.510638 (2880 3725);
FORCEPROP 1 LASTPIN (2825 3750) $PN 1
J 0
(2830 3712);
DISPLAY 0.787234 (2830 3712);
PAINT MONO (2830 3712);
FORCEPROP 1 LASTPIN (2825 3550) $PN 2
J 0
(2830 3560);
DISPLAY 0.787234 (2830 3560);
PAINT MONO (2830 3560);
FORCEPROP 1 LAST PATH I97
J 0
(2875 3825);
DISPLAY 0.978723 (2875 3825);
PAINT WHITE (2875 3825);
DISPLAY INVISIBLE (2875 3825);
FORCEPROP 2 LAST CDS_LIB pure_quanta
J 0
(2825 3650);
DISPLAY INVISIBLE (2825 3650);
FORCEPROP 2 LAST CDS_LOCATION R2791
J 0
(2875 3900);
DISPLAY 1.021277 (2875 3900);
DISPLAY INVISIBLE (2875 3900);
FORCEPROP 2 LAST $SEC 1
J 0
(2875 3900);
DISPLAY 0.680851 (2875 3900);
PAINT MONO (2875 3900);
DISPLAY INVISIBLE (2875 3900);
FORCEPROP 2 LAST CDS_SEC 1
J 0
(2875 3900);
DISPLAY 1.021277 (2875 3900);
DISPLAY INVISIBLE (2875 3900);
FORCEADD Q_RES..2
(-1950 375);
FORCEPROP 1 LAST PART_NUMBER CS00002JB13
J 0
(-1930 325);
DISPLAY 0.510638 (-1930 325);
DISPLAY INVISIBLE (-1930 325);
FORCEPROP 1 LAST VALUE 0
J 0
(-1925 425);
DISPLAY 0.510638 (-1925 425);
FORCEPROP 1 LAST MATERIAL EMPTY
J 0
(-1925 325);
DISPLAY 0.510638 (-1925 325);
PAINT RED (-1925 325);
FORCEPROP 0 LAST ROOM USB1_BOM2
J 0
(-1950 500);
DISPLAY 0.808511 (-1950 500);
FORCEPROP 1 LAST $LOCATION R2789
J 0
(-1925 375);
DISPLAY 0.510638 (-1925 375);
FORCEPROP 1 LASTPIN (-1950 475) $PN 1
J 0
(-1945 437);
DISPLAY 0.787234 (-1945 437);
PAINT MONO (-1945 437);
FORCEPROP 1 LASTPIN (-1950 275) $PN 2
J 0
(-1960 285);
DISPLAY 0.787234 (-1960 285);
PAINT MONO (-1960 285);
FORCEPROP 1 LAST PATH I98
J 0
(-1900 550);
DISPLAY 0.978723 (-1900 550);
PAINT WHITE (-1900 550);
DISPLAY INVISIBLE (-1900 550);
FORCEPROP 2 LAST CDS_LIB pure_quanta
J 0
(-1950 375);
DISPLAY INVISIBLE (-1950 375);
FORCEPROP 1 LAST PACK_TYPE 0402LF
J 0
(-1930 275);
DISPLAY 0.510638 (-1930 275);
DISPLAY INVISIBLE (-1930 275);
FORCEPROP 1 LAST TOLERANCE 5%
J 0
(-1925 475);
DISPLAY 0.510638 (-1925 475);
DISPLAY INVISIBLE (-1925 475);
FORCEPROP 1 LAST WATTAGE 1/16W
J 0
(-1930 425);
DISPLAY 0.510638 (-1930 425);
DISPLAY INVISIBLE (-1930 425);
FORCEPROP 2 LAST CDS_LOCATION R2789
J 0
(-1900 600);
DISPLAY 1.021277 (-1900 600);
DISPLAY INVISIBLE (-1900 600);
FORCEPROP 2 LAST $SEC 1
J 0
(-1900 600);
DISPLAY 0.680851 (-1900 600);
PAINT MONO (-1900 600);
DISPLAY INVISIBLE (-1900 600);
FORCEPROP 2 LAST CDS_SEC 1
J 0
(-1900 600);
DISPLAY 1.021277 (-1900 600);
DISPLAY INVISIBLE (-1900 600);
FORCEADD Q_RES..2
(-2025 375);
FORCEPROP 1 LAST PART_NUMBER CS00002JB13
J 0
(-2400 350);
DISPLAY 0.638298 (-2400 350);
DISPLAY INVISIBLE (-2400 350);
FORCEPROP 1 LAST PACK_TYPE 0402LF
J 0
(-2225 300);
DISPLAY 0.638298 (-2225 300);
FORCEPROP 1 LAST VALUE 0
J 0
(-2100 550);
DISPLAY 0.638298 (-2100 550);
FORCEPROP 1 LAST WATTAGE 1/16W
J 0
(-2225 450);
DISPLAY 0.638298 (-2225 450);
FORCEPROP 1 LAST TOLERANCE 5%
J 0
(-2125 500);
DISPLAY 0.638298 (-2125 500);
FORCEPROP 1 LAST MATERIAL EMPTY
J 0
(-2200 400);
DISPLAY 0.638298 (-2200 400);
PAINT RED (-2200 400);
FORCEPROP 0 LAST ROOM USB1_BOM2
J 0
(-2325 650);
DISPLAY 0.638298 (-2325 650);
FORCEPROP 1 LAST $LOCATION R2788
J 0
(-2175 600);
DISPLAY 0.638298 (-2175 600);
FORCEPROP 1 LASTPIN (-2025 475) $PN 1
J 0
(-2020 437);
DISPLAY 0.787234 (-2020 437);
PAINT MONO (-2020 437);
FORCEPROP 1 LASTPIN (-2025 275) $PN 2
J 0
(-2020 285);
DISPLAY 0.787234 (-2020 285);
PAINT MONO (-2020 285);
FORCEPROP 1 LAST PATH I99
J 0
(-1975 550);
DISPLAY 0.978723 (-1975 550);
PAINT WHITE (-1975 550);
DISPLAY INVISIBLE (-1975 550);
FORCEPROP 2 LAST CDS_LIB pure_quanta
J 0
(-2025 375);
DISPLAY INVISIBLE (-2025 375);
FORCEPROP 2 LAST CDS_LOCATION R2788
J 0
(-1975 600);
DISPLAY 1.021277 (-1975 600);
DISPLAY INVISIBLE (-1975 600);
FORCEPROP 2 LAST $SEC 1
J 0
(-1975 600);
DISPLAY 0.680851 (-1975 600);
PAINT MONO (-1975 600);
DISPLAY INVISIBLE (-1975 600);
FORCEPROP 2 LAST CDS_SEC 1
J 0
(-1975 600);
DISPLAY 1.021277 (-1975 600);
DISPLAY INVISIBLE (-1975 600);
FORCEADD QUANTA_TITLE_BLOCK_C..1
(4825 -925);
FORCEPROP 0 LAST CDS_CON_LAST_MODIFIED Fri Aug 25 14:02:14 2023
J 0
(2940 -910);
DISPLAY INVISIBLE (2940 -910);
FORCEPROP 1 LAST CUSTOM_TXT_CDS <CON_LAST_MODIFIED>
J 0
(2940 -910);
DISPLAY 0.978723 (2940 -910);
FORCEPROP 2 LAST CUSTOM_TXT_CDS <XR_PAGE_TITLE>
J 0
(-3065 4325);
DISPLAY 0.638298 (-3065 4325);
PAINT PINK (-3065 4325);
DISPLAY INVISIBLE (-3065 4325);
FORCEPROP 1 LAST CUSTOM_TXT_CDS <NAME_2>
J 0
(1650 -875);
FORCEPROP 1 LAST CUSTOM_TXT_CDS <NAME_1>
J 0
(1650 -750);
FORCEPROP 1 LAST CUSTOM_TXT_CDS <Q_NUMBER>
J 0
(3422 -822);
DISPLAY 1.212766 (3422 -822);
FORCEPROP 1 LAST CUSTOM_TXT_CDS <Q_PROJ>
J 0
(2443 -823);
DISPLAY 1.212766 (2443 -823);
FORCEPROP 1 LAST CUSTOM_TXT_CDS <Q_REV>
J 0
(4641 -822);
DISPLAY 1.212766 (4641 -822);
FORCEPROP 1 LAST CUSTOM_TXT_CDS <CON_PAGE_NUM> OF <CON_TOTAL_PAGES>
J 0
(4379 -907);
DISPLAY 0.978723 (4379 -907);
FORCEPROP 1 LAST Q_TITLE USB HUB
J 0
(-4541 -899);
DISPLAY 2.446809 (-4541 -899);
PAINT GREEN (-4541 -899);
FORCEPROP 1 LAST Q_DEPT 
J 1
(1062 -876);
DISPLAY 1.957447 (1062 -876);
PAINT GREEN (1062 -876);
FORCEPROP 2 LAST CDS_XR_PAGE_TITLE CR-152 : @S9S_MB_2U_LIB.S9S_MB_2U(SCH_1):PAGE152
J 0
(-3065 4325);
DISPLAY 0.638298 (-3065 4325);
PAINT PINK (-3065 4325);
DISPLAY INVISIBLE (-3065 4325);
FORCEPROP 2 LAST PAGE_BORDER TRUE
J 0
(-3065 4325);
DISPLAY 0.638298 (-3065 4325);
PAINT PINK (-3065 4325);
DISPLAY INVISIBLE (-3065 4325);
FORCEPROP 1 LAST CDS_LMAN_SYM_OUTLINE -9475,6775,100,-125
J 0
(4825 -925);
DISPLAY 0.468085 (4825 -925);
PAINT GREEN (4825 -925);
DISPLAY INVISIBLE (4825 -925);
FORCEPROP 2 LAST CDS_LIB pure_quanta
J 0
(4825 -925);
DISPLAY INVISIBLE (4825 -925);
FORCEPROP 1 LAST COMMENT_BODY TRUE
J 0
(4837 -938);
DISPLAY 0.978723 (4837 -938);
PAINT GREEN (4837 -938);
DISPLAY INVISIBLE (4837 -938);
FORCEADD CAD_NOTE..1
(3375 3325);
FORCEPROP 0 LAST S1 R2790/R3651,R3652/R2791 CO-LAYOUT
J 0
(3250 3200);
DISPLAY 0.808511 (3250 3200);
PAINT WHITE (3250 3200);
FORCEPROP 1 LAST COMMENT_BODY TRUE
J 0
(3400 3425);
DISPLAY 0.978723 (3400 3425);
DISPLAY INVISIBLE (3400 3425);
FORCEPROP 2 LAST CDS_LIB logical_power
J 0
(3375 3325);
DISPLAY INVISIBLE (3375 3325);
FORCEADD CAD_NOTE..1
(1550 475);
FORCEPROP 0 LAST S1 SHORT THE NET USB2_HUB_SWB_R_DP/DN TO USB2_HUB_BUF_SWB_R_DP/DN
J 0
(1425 350);
DISPLAY 0.808511 (1425 350);
PAINT WHITE (1425 350);
FORCEPROP 1 LAST COMMENT_BODY TRUE
J 0
(1575 575);
DISPLAY 0.978723 (1575 575);
DISPLAY INVISIBLE (1575 575);
FORCEPROP 2 LAST CDS_LIB logical_power
J 0
(1550 475);
DISPLAY INVISIBLE (1550 475);
FORCEADD DNS..1
R 1
(100 750);
PAINT RED (100 750);
FORCEPROP 1 LAST COMMENT_BODY TRUE
R 2
J 0
(325 825);
DISPLAY 0.872340 (325 825);
PAINT GREEN (325 825);
DISPLAY INVISIBLE (325 825);
FORCEPROP 2 LAST CDS_LIB mstr_misc
J 0
(100 750);
DISPLAY INVISIBLE (100 750);
FORCEADD DNS..1
R 1
(600 725);
PAINT RED (600 725);
FORCEPROP 1 LAST COMMENT_BODY TRUE
R 2
J 0
(825 800);
DISPLAY 0.872340 (825 800);
PAINT GREEN (825 800);
DISPLAY INVISIBLE (825 800);
FORCEPROP 2 LAST CDS_LIB mstr_misc
J 0
(600 725);
DISPLAY INVISIBLE (600 725);
FORCEADD DNS..1
R 1
(1500 -200);
PAINT RED (1500 -200);
FORCEPROP 1 LAST COMMENT_BODY TRUE
R 2
J 0
(1725 -125);
DISPLAY 0.872340 (1725 -125);
PAINT GREEN (1725 -125);
DISPLAY INVISIBLE (1725 -125);
FORCEPROP 2 LAST CDS_LIB mstr_misc
J 0
(1500 -200);
DISPLAY INVISIBLE (1500 -200);
FORCEADD DNS..1
R 1
(-125 75);
PAINT RED (-125 75);
FORCEPROP 1 LAST COMMENT_BODY TRUE
R 2
J 0
(100 150);
DISPLAY 0.872340 (100 150);
PAINT GREEN (100 150);
DISPLAY INVISIBLE (100 150);
FORCEPROP 2 LAST CDS_LIB mstr_misc
J 0
(-125 75);
DISPLAY INVISIBLE (-125 75);
FORCEADD DNS..1
R 1
(-675 -275);
PAINT RED (-675 -275);
FORCEPROP 1 LAST COMMENT_BODY TRUE
R 2
J 0
(-450 -200);
DISPLAY 0.872340 (-450 -200);
PAINT GREEN (-450 -200);
DISPLAY INVISIBLE (-450 -200);
FORCEPROP 2 LAST CDS_LIB mstr_misc
J 0
(-675 -275);
DISPLAY INVISIBLE (-675 -275);
FORCEADD DNS..1
R 1
(-1150 -250);
PAINT RED (-1150 -250);
FORCEPROP 1 LAST COMMENT_BODY TRUE
R 2
J 0
(-925 -175);
DISPLAY 0.872340 (-925 -175);
PAINT GREEN (-925 -175);
DISPLAY INVISIBLE (-925 -175);
FORCEPROP 2 LAST CDS_LIB mstr_misc
J 0
(-1150 -250);
DISPLAY INVISIBLE (-1150 -250);
FORCEADD DNS..2
(2775 3650);
PAINT RED (2775 3650);
FORCEPROP 1 LAST COMMENT_BODY TRUE
R 1
J 0
(2850 3425);
DISPLAY 0.872340 (2850 3425);
PAINT GREEN (2850 3425);
DISPLAY INVISIBLE (2850 3425);
FORCEPROP 2 LAST CDS_LIB mstr_misc
J 0
(2775 3650);
DISPLAY INVISIBLE (2775 3650);
FORCEADD DNS..1
(-1900 3075);
PAINT RED (-1900 3075);
FORCEPROP 1 LAST COMMENT_BODY TRUE
R 1
J 0
(-1825 2850);
DISPLAY 0.872340 (-1825 2850);
PAINT GREEN (-1825 2850);
DISPLAY INVISIBLE (-1825 2850);
FORCEPROP 2 LAST CDS_LIB mstr_misc
J 0
(-1900 3075);
DISPLAY INVISIBLE (-1900 3075);
FORCEADD DNS..1
(-4125 2350);
PAINT RED (-4125 2350);
FORCEPROP 1 LAST COMMENT_BODY TRUE
R 1
J 0
(-4050 2125);
DISPLAY 0.872340 (-4050 2125);
PAINT GREEN (-4050 2125);
DISPLAY INVISIBLE (-4050 2125);
FORCEPROP 2 LAST CDS_LIB mstr_misc
J 0
(-4125 2350);
DISPLAY INVISIBLE (-4125 2350);
FORCEADD DNS..1
(-1525 1875);
PAINT RED (-1525 1875);
FORCEPROP 1 LAST COMMENT_BODY TRUE
R 1
J 0
(-1450 1650);
DISPLAY 0.872340 (-1450 1650);
PAINT GREEN (-1450 1650);
DISPLAY INVISIBLE (-1450 1650);
FORCEPROP 2 LAST CDS_LIB mstr_misc
J 0
(-1525 1875);
DISPLAY INVISIBLE (-1525 1875);
FORCEADD DNS..1
(-1525 2000);
PAINT RED (-1525 2000);
FORCEPROP 1 LAST COMMENT_BODY TRUE
R 1
J 0
(-1450 1775);
DISPLAY 0.872340 (-1450 1775);
PAINT GREEN (-1450 1775);
DISPLAY INVISIBLE (-1450 1775);
FORCEPROP 2 LAST CDS_LIB mstr_misc
J 0
(-1525 2000);
DISPLAY INVISIBLE (-1525 2000);
FORCEADD DNS..1
(-1525 2125);
PAINT RED (-1525 2125);
FORCEPROP 1 LAST COMMENT_BODY TRUE
R 1
J 0
(-1450 1900);
DISPLAY 0.872340 (-1450 1900);
PAINT GREEN (-1450 1900);
DISPLAY INVISIBLE (-1450 1900);
FORCEPROP 2 LAST CDS_LIB mstr_misc
J 0
(-1525 2125);
DISPLAY INVISIBLE (-1525 2125);
FORCEADD DNS..1
(-1525 2275);
PAINT RED (-1525 2275);
FORCEPROP 1 LAST COMMENT_BODY TRUE
R 1
J 0
(-1450 2050);
DISPLAY 0.872340 (-1450 2050);
PAINT GREEN (-1450 2050);
DISPLAY INVISIBLE (-1450 2050);
FORCEPROP 2 LAST CDS_LIB mstr_misc
J 0
(-1525 2275);
DISPLAY INVISIBLE (-1525 2275);
FORCEADD DNS..2
(3625 3650);
PAINT RED (3625 3650);
FORCEPROP 1 LAST COMMENT_BODY TRUE
R 1
J 0
(3700 3425);
DISPLAY 0.872340 (3700 3425);
PAINT GREEN (3700 3425);
DISPLAY INVISIBLE (3700 3425);
FORCEPROP 2 LAST CDS_LIB mstr_misc
J 0
(3625 3650);
DISPLAY INVISIBLE (3625 3650);
FORCEADD DNS..2
(3450 3650);
PAINT RED (3450 3650);
FORCEPROP 1 LAST COMMENT_BODY TRUE
R 1
J 0
(3525 3425);
DISPLAY 0.872340 (3525 3425);
PAINT GREEN (3525 3425);
DISPLAY INVISIBLE (3525 3425);
FORCEPROP 2 LAST CDS_LIB mstr_misc
J 0
(3450 3650);
DISPLAY INVISIBLE (3450 3650);
FORCEADD CAD_NOTE..1
(-1750 900);
FORCEPROP 0 LAST S1 R2788/R2786,R2789/R2787 CO-LAYOUT
J 0
(-1875 775);
DISPLAY 0.808511 (-1875 775);
PAINT WHITE (-1875 775);
FORCEPROP 1 LAST COMMENT_BODY TRUE
J 0
(-1725 1000);
DISPLAY 0.978723 (-1725 1000);
DISPLAY INVISIBLE (-1725 1000);
FORCEPROP 2 LAST CDS_LIB logical_power
J 0
(-1750 900);
DISPLAY INVISIBLE (-1750 900);
FORCEADD DNS..2
(-2275 1000);
PAINT RED (-2275 1000);
FORCEPROP 1 LAST COMMENT_BODY TRUE
R 1
J 0
(-2200 775);
DISPLAY 0.872340 (-2200 775);
PAINT GREEN (-2200 775);
DISPLAY INVISIBLE (-2200 775);
FORCEPROP 2 LAST CDS_LIB mstr_misc
J 0
(-2275 1000);
DISPLAY INVISIBLE (-2275 1000);
FORCEADD DNS..2
(-2450 1000);
PAINT RED (-2450 1000);
FORCEPROP 1 LAST COMMENT_BODY TRUE
R 1
J 0
(-2375 775);
DISPLAY 0.872340 (-2375 775);
PAINT GREEN (-2375 775);
DISPLAY INVISIBLE (-2375 775);
FORCEPROP 2 LAST CDS_LIB mstr_misc
J 0
(-2450 1000);
DISPLAY INVISIBLE (-2450 1000);
FORCEADD DNS..2
(-1975 375);
PAINT RED (-1975 375);
FORCEPROP 1 LAST COMMENT_BODY TRUE
R 1
J 0
(-1900 150);
DISPLAY 0.872340 (-1900 150);
PAINT GREEN (-1900 150);
DISPLAY INVISIBLE (-1900 150);
FORCEPROP 2 LAST CDS_LIB mstr_misc
J 0
(-1975 375);
DISPLAY INVISIBLE (-1975 375);
WIRE 16 -1 (1125 1000)(1125 900);
WIRE 16 -1 (-4150 3350)(-4150 3050);
WIRE 16 -1 (-4000 4900)(-4000 4800);
WIRE 16 -1 (-1900 4025)(-1900 3875);
WIRE 16 -1 (-2175 2475)(-2175 2275);
WIRE 16 -1 (575 500)(575 425);
WIRE 16 -1 (75 500)(575 500);
WIRE 16 -1 (575 625)(575 500);
WIRE 16 -1 (1375 -100)(1375 25);
WIRE 16 -1 (1475 -300)(1475 -375);
WIRE 16 -1 (-675 -350)(-675 -400);
WIRE 16 -1 (-1150 -325)(-1150 -400);
WIRE 16 -1 (725 3325)(725 3175);
WIRE 16 -1 (600 3325)(725 3325);
WIRE 16 -1 (-750 2975)(-750 2850);
WIRE 16 -1 (-1075 3000)(-1075 2875);
WIRE 16 -1 (-2275 2925)(-2275 2900);
WIRE 16 -1 (-1900 2925)(-2275 2925);
WIRE 16 -1 (-2275 3050)(-2275 2925);
WIRE 16 -1 (4475 4275)(4475 4200);
WIRE 16 -1 (4350 4425)(4350 4375);
WIRE 16 -1 (4300 4425)(4350 4425);
WIRE 16 -1 (3700 4425)(3700 4375);
WIRE 16 -1 (3750 4425)(3700 4425);
WIRE 16 -1 (3475 4275)(3475 4200);
WIRE 16 -1 (-3450 4225)(-3450 4150);
WIRE 16 -1 (-3450 4225)(-3075 4225);
WIRE 16 -1 (-3450 4400)(-3450 4225);
WIRE 16 -1 (-4150 1975)(-4150 2250);
WIRE 16 -1 (1475 4275)(1975 4275);
WIRE 16 -1 (3625 3500)(3625 3575);
WIRE 16 -1 (3450 3500)(3450 3575);
WIRE 16 -1 (-2275 850)(-2275 925);
WIRE 16 -1 (-2450 850)(-2450 925);
WIRE 16 -1 (4475 4625)(4475 4475);
WIRE 16 -1 (4300 4625)(4475 4625);
WIRE 16 -1 (4800 4625)(4475 4625);
WIRE 16 -1 (4800 4075)(4800 4625);
WIRE 16 -1 (600 4075)(4800 4075);
FORCEPROP 2 LAST SIG_NAME USB_HUB_XTAL_OUT
J 0
(740 4085);
DISPLAY 0.638298 (740 4085);
PAINT WHITE (740 4085);
WIRE 16 -1 (600 4125)(3150 4125);
FORCEPROP 2 LAST SIG_NAME USB_HUB_XTAL_IN
J 0
(740 4135);
DISPLAY 0.638298 (740 4135);
PAINT WHITE (740 4135);
WIRE 16 -1 (3150 4625)(3150 4125);
WIRE 16 -1 (3475 4625)(3475 4475);
WIRE 16 -1 (3475 4625)(3150 4625);
WIRE 16 -1 (3750 4625)(3475 4625);
WIRE 16 2175 (4425 4600)(4725 4600);
WIRE 16 2175 (4725 4600)(4725 4225);
WIRE 16 2175 (4425 4600)(4425 4225);
WIRE 16 2175 (4425 4225)(4725 4225);
WIRE 16 2175 (3350 4600)(3650 4600);
WIRE 16 2175 (3650 4600)(3650 4225);
WIRE 16 2175 (3350 4600)(3350 4225);
WIRE 16 2175 (3350 4225)(3650 4225);
WIRE 16 -1 (2725 3750)(2725 3925);
WIRE 16 -1 (2725 3925)(2650 3925);
WIRE 16 -1 (2725 3925)(3450 3925);
FORCEPROP 2 LAST SIG_NAME USB2_HOST_BMC_B_DP
J 0
(2790 3935);
DISPLAY 0.723404 (2790 3935);
PAINT WHITE (2790 3935);
WIRE 16 -1 (4150 3925)(3450 3925);
WIRE 16 -1 (3450 3775)(3450 3925);
WIRE 16 2175 (2425 3375)(3175 3375);
WIRE 16 2175 (3175 4000)(3175 3375);
WIRE 16 2175 (2425 4000)(2425 3375);
WIRE 16 2175 (2425 4000)(3175 4000);
WIRE 16 -1 (1475 75)(1475 -100);
WIRE 16 -1 (250 75)(1475 75);
FORCEPROP 2 LAST SIG_NAME PD_U5201_VREG
J 0
(365 85);
DISPLAY 0.723404 (365 85);
PAINT WHITE (365 85);
WIRE 16 -1 (-1150 25)(-1150 -125);
WIRE 16 -1 (-500 25)(-1150 25);
FORCEPROP 2 LAST SIG_NAME PD_U5201_RSTN
J 0
(-1060 35);
DISPLAY 0.723404 (-1060 35);
PAINT WHITE (-1060 35);
WIRE 16 -1 (75 900)(75 850);
WIRE 16 -1 (1125 125)(250 125);
WIRE 16 -1 (575 900)(75 900);
WIRE 16 -1 (575 825)(575 900);
WIRE 16 -1 (575 900)(1125 900);
WIRE 16 -1 (1125 900)(1125 125);
WIRE 16 -1 (75 650)(75 500);
WIRE 16 -1 (-2275 1125)(-2275 1200);
WIRE 16 -1 (-2275 1200)(-1950 1200);
WIRE 16 -1 (-1950 475)(-1950 1200);
WIRE 16 -1 (-1950 1325)(-1950 1200);
WIRE 16 -1 (2825 1325)(-1950 1325);
FORCEPROP 2 LAST SIG_NAME USB2_HOST_BMC_B_BUF_DN
J 0
(-160 1335);
DISPLAY 0.808511 (-160 1335);
PAINT WHITE (-160 1335);
WIRE 16 -1 (2825 3550)(2825 1325);
WIRE 16 -1 (-2450 1125)(-2450 1250);
WIRE 16 -1 (-2450 1250)(-2025 1250);
WIRE 16 -1 (-2025 475)(-2025 1250);
WIRE 16 -1 (-2025 1425)(-2025 1250);
WIRE 16 -1 (2725 1425)(-2025 1425);
FORCEPROP 2 LAST SIG_NAME USB2_HOST_BMC_B_BUF_DP
J 0
(-160 1435);
DISPLAY 0.808511 (-160 1435);
PAINT WHITE (-160 1435);
WIRE 16 -1 (2725 3550)(2725 1425);
WIRE 16 -1 (-2275 3250)(-2275 3375);
WIRE 16 -1 (-2275 3375)(-1900 3375);
WIRE 16 -1 (-1900 3375)(-1900 3200);
WIRE 16 -1 (-1900 3375)(-1900 3425);
WIRE 16 -1 (-1900 3425)(-1900 3675);
WIRE 16 -1 (-350 3425)(-1900 3425);
WIRE 16 -1 (-2625 3425)(-1900 3425);
FORCEPROP 2 LAST SIG_NAME RST_USB_HUB_R_N
J 0
(-2485 3435);
DISPLAY 0.723404 (-2485 3435);
PAINT WHITE (-2485 3435);
WIRE 16 -1 (-2175 1875)(-1650 1875);
WIRE 16 -1 (-2175 2000)(-2175 1875);
WIRE 16 -1 (-1650 2000)(-2175 2000);
WIRE 16 -1 (-2175 2125)(-2175 2000);
WIRE 16 -1 (-1650 2125)(-2175 2125);
WIRE 16 -1 (-2175 2275)(-2175 2125);
WIRE 16 -1 (-1650 2275)(-2175 2275);
WIRE 16 -1 (1475 225)(3050 225);
FORCEPROP 2 LAST SIG_NAME USB2_HUB_BUF_SWB_DP
J 0
(2115 235);
DISPLAY 0.723404 (2115 235);
PAINT WHITE (2115 235);
WIRE 16 -1 (1475 175)(3050 175);
FORCEPROP 2 LAST SIG_NAME USB2_HUB_BUF_SWB_DN
J 0
(2115 185);
DISPLAY 0.723404 (2115 185);
PAINT WHITE (2115 185);
WIRE 16 2175 (-2400 725)(-1522 725);
WIRE 16 2175 (-1522 725)(-1522 125);
WIRE 16 2175 (-2400 725)(-2400 125);
WIRE 16 2175 (-2400 125)(-1522 125);
WIRE 16 -1 (-2025 225)(-2075 225);
WIRE 16 -1 (-2025 275)(-2025 225);
WIRE 16 -1 (-500 225)(-2025 225);
FORCEPROP 2 LAST SIG_NAME USB2_HUB_BUF_SWB_R_DP
J 0
(-1405 225);
DISPLAY 0.808511 (-1405 225);
PAINT WHITE (-1405 225);
FORCEPROP 2 LASTPROP $XR0 152 
J 0
(-1675 225);
DISPLAY 0.638298 (-1675 225);
PAINT MONO (-1675 225);
WIRE 16 -1 (250 25)(1375 25);
WIRE 16 -1 (250 -25)(1125 -25);
FORCEPROP 2 LAST SIG_NAME TP_USB2_ENA_HS
J 0
(365 -15);
DISPLAY 0.723404 (365 -15);
PAINT WHITE (365 -15);
WIRE 16 -1 (-1375 75)(-500 75);
FORCEPROP 2 LAST SIG_NAME TP_USB2_CD
J 0
(-1060 85);
DISPLAY 0.723404 (-1060 85);
PAINT WHITE (-1060 85);
WIRE 16 -1 (250 225)(1275 225);
FORCEPROP 2 LAST SIG_NAME USB2_HUB_BUF_SWB_R_DP
J 0
(365 235);
DISPLAY 0.723404 (365 235);
PAINT WHITE (365 235);
FORCEPROP 2 LASTPROP $XR0 152 
J 0
(149 235);
DISPLAY 0.638298 (149 235);
PAINT MONO (149 235);
WIRE 16 -1 (-1950 175)(-2075 175);
WIRE 16 -1 (-1950 275)(-1950 175);
WIRE 16 -1 (-500 175)(-1950 175);
FORCEPROP 2 LAST SIG_NAME USB2_HUB_BUF_SWB_R_DN
J 0
(-1405 175);
DISPLAY 0.808511 (-1405 175);
PAINT WHITE (-1405 175);
FORCEPROP 2 LASTPROP $XR0 152 
J 0
(-1675 175);
DISPLAY 0.638298 (-1675 175);
PAINT MONO (-1675 175);
WIRE 16 -1 (3625 3775)(3625 3875);
WIRE 16 -1 (4150 3875)(3625 3875);
WIRE 16 -1 (2825 3875)(2650 3875);
FORCEPROP 2 LAST SIG_NAME USB2_HOST_BMC_B_DN
J 0
(2790 3885);
DISPLAY 0.723404 (2790 3885);
PAINT WHITE (2790 3885);
WIRE 16 -1 (2825 3750)(2825 3875);
WIRE 16 -1 (2825 3875)(3625 3875);
WIRE 16 -1 (600 3925)(2450 3925);
FORCEPROP 2 LAST SIG_NAME USB2_P0_R_DP
J 0
(740 3935);
DISPLAY 0.723404 (740 3935);
PAINT WHITE (740 3935);
WIRE 16 -1 (600 3875)(2450 3875);
FORCEPROP 2 LAST SIG_NAME USB2_P0_R_DN
J 0
(740 3885);
DISPLAY 0.723404 (740 3885);
PAINT WHITE (740 3885);
WIRE 16 -1 (1625 3825)(600 3825);
FORCEPROP 2 LAST SIG_NAME USB2_HUB_SWB_DP
J 0
(740 3835);
DISPLAY 0.723404 (740 3835);
PAINT WHITE (740 3835);
WIRE 16 -1 (1625 3775)(600 3775);
FORCEPROP 2 LAST SIG_NAME USB2_HUB_SWB_DN
J 0
(740 3785);
DISPLAY 0.723404 (740 3785);
PAINT WHITE (740 3785);
WIRE 16 -1 (600 3725)(1325 3725);
FORCEPROP 0 LAST SIG_NAME NC_USB_HUB_DP2
J 0
(740 3735);
DISPLAY 0.723404 (740 3735);
PAINT WHITE (740 3735);
WIRE 16 -1 (600 3675)(1325 3675);
FORCEPROP 0 LAST SIG_NAME NC_USB_HUB_DM2
J 0
(740 3685);
DISPLAY 0.723404 (740 3685);
PAINT WHITE (740 3685);
WIRE 16 -1 (600 3625)(1325 3625);
FORCEPROP 0 LAST SIG_NAME NC_USB_HUB_DP3
J 0
(740 3635);
DISPLAY 0.723404 (740 3635);
PAINT WHITE (740 3635);
WIRE 16 -1 (600 3475)(1325 3475);
FORCEPROP 0 LAST SIG_NAME NC_USB_HUB_DM4
J 0
(740 3485);
DISPLAY 0.723404 (740 3485);
PAINT WHITE (740 3485);
WIRE 16 -1 (-3850 4800)(-4000 4800);
WIRE 16 -1 (-1900 3000)(-1900 2925);
WIRE 16 -1 (-825 4400)(-825 4225);
WIRE 16 -1 (-1175 4400)(-1175 4225);
WIRE 16 -1 (-825 4225)(-1175 4225);
WIRE 16 -1 (-1550 4400)(-1550 4225);
WIRE 16 -1 (-1175 4225)(-1550 4225);
WIRE 16 -1 (-1925 4400)(-1925 4225);
WIRE 16 -1 (-1550 4225)(-1925 4225);
WIRE 16 -1 (-2300 4400)(-2300 4225);
WIRE 16 -1 (-2300 4225)(-1925 4225);
WIRE 16 -1 (-2675 4400)(-2675 4225);
WIRE 16 -1 (-2675 4225)(-2300 4225);
WIRE 16 -1 (-3075 4225)(-2675 4225);
WIRE 16 -1 (-3075 4400)(-3075 4225);
WIRE 16 -1 (-3500 175)(-2275 175);
FORCEPROP 2 LAST SIG_NAME USB2_HUB_SWB_DN
J 0
(-3485 185);
DISPLAY 0.723404 (-3485 185);
PAINT WHITE (-3485 185);
WIRE 16 -1 (-3500 225)(-2275 225);
FORCEPROP 2 LAST SIG_NAME USB2_HUB_SWB_DP
J 0
(-3485 235);
DISPLAY 0.723404 (-3485 235);
PAINT WHITE (-3485 235);
WIRE 16 -1 (-1125 3925)(-1300 3925);
WIRE 16 -1 (-1300 3925)(-1300 4025);
WIRE 16 -1 (-1300 4025)(-500 4025);
WIRE 16 -1 (-500 4025)(-350 4025);
WIRE 16 -1 (-500 4075)(-500 4025);
WIRE 16 -1 (-500 4075)(-350 4075);
WIRE 16 -1 (-500 4125)(-500 4075);
WIRE 16 -1 (-350 4125)(-500 4125);
WIRE 16 -1 (-500 4125)(-500 4225);
WIRE 16 -1 (-350 4225)(-500 4225);
WIRE 16 -1 (-500 4225)(-500 4325);
WIRE 16 -1 (-350 4325)(-500 4325);
WIRE 16 -1 (-500 4325)(-500 4800);
WIRE 16 -1 (-825 4600)(-825 4800);
WIRE 16 -1 (-500 4800)(-825 4800);
WIRE 16 -1 (-1175 4600)(-1175 4800);
WIRE 16 -1 (-825 4800)(-1175 4800);
WIRE 16 -1 (-1550 4800)(-1550 4600);
WIRE 16 -1 (-1175 4800)(-1550 4800);
WIRE 16 -1 (-1925 4800)(-1925 4600);
WIRE 16 -1 (-1550 4800)(-1925 4800);
WIRE 16 -1 (-2300 4800)(-2300 4600);
WIRE 16 -1 (-1925 4800)(-2300 4800);
WIRE 16 -1 (-2675 4600)(-2675 4800);
WIRE 16 -1 (-2300 4800)(-2675 4800);
WIRE 16 -1 (-3075 4600)(-3075 4800);
WIRE 16 -1 (-2675 4800)(-3075 4800);
WIRE 16 -1 (-3450 4800)(-3650 4800);
FORCEPROP 2 LAST SIG_NAME P3V3_AUX_USB_HUB
J 0
(-3460 4810);
DISPLAY 0.510638 (-3460 4810);
PAINT WHITE (-3460 4810);
WIRE 16 -1 (-3450 4800)(-3450 4600);
WIRE 16 -1 (-3450 4800)(-3075 4800);
WIRE 16 -1 (-925 3925)(-350 3925);
FORCEPROP 2 LAST SIG_NAME USB_HUB_DVDD
J 0
(-810 3935);
DISPLAY 0.638298 (-810 3935);
PAINT WHITE (-810 3935);
WIRE 16 -1 (-350 3775)(-925 3775);
FORCEPROP 2 LAST SIG_NAME USB_HUB_OVCUR1
J 0
(-910 3785);
DISPLAY 0.723404 (-910 3785);
PAINT WHITE (-910 3785);
WIRE 16 -1 (-350 3625)(-925 3625);
FORCEPROP 2 LAST SIG_NAME USB_HUB_OVCUR4
J 0
(-910 3635);
DISPLAY 0.723404 (-910 3635);
PAINT WHITE (-910 3635);
WIRE 16 -1 (-1075 3475)(-1075 3200);
WIRE 16 -1 (-350 3475)(-1075 3475);
FORCEPROP 2 LAST SIG_NAME USB_HUB_RREF
J 0
(-910 3485);
DISPLAY 0.808511 (-910 3485);
PAINT WHITE (-910 3485);
WIRE 16 -1 (-750 3325)(-750 3175);
WIRE 16 -1 (-350 3325)(-750 3325);
FORCEPROP 2 LAST SIG_NAME USB_HUB_PGANG
J 0
(-785 3335);
DISPLAY 0.510638 (-785 3335);
PAINT WHITE (-785 3335);
WIRE 16 -1 (600 4325)(1275 4325);
FORCEPROP 0 LAST SIG_NAME NC_USB_HUB_SDA
J 0
(690 4335);
DISPLAY 0.723404 (690 4335);
PAINT WHITE (690 4335);
WIRE 16 -1 (-4150 2450)(-4150 2625);
WIRE 16 -1 (-3075 2625)(-4150 2625);
FORCEPROP 2 LAST SIG_NAME USB_HUB_PSELF
J 0
(-3810 2635);
DISPLAY 0.808511 (-3810 2635);
PAINT WHITE (-3810 2635);
WIRE 16 -1 (-4150 2850)(-4150 2625);
WIRE 16 -1 (-875 2275)(-1450 2275);
FORCEPROP 2 LAST SIG_NAME USB_HUB_OVCUR1
J 0
(-1435 2285);
DISPLAY 0.723404 (-1435 2285);
PAINT WHITE (-1435 2285);
WIRE 16 -1 (-350 3375)(-825 3375);
FORCEPROP 2 LAST SIG_NAME USB_HUB_PSELF
J 0
(-785 3385);
DISPLAY 0.510638 (-785 3385);
PAINT WHITE (-785 3385);
WIRE 16 -1 (-2825 3425)(-3475 3425);
FORCEPROP 2 LAST SIG_NAME RST_USB_HUB_N
J 0
(-3460 3435);
DISPLAY 0.723404 (-3460 3435);
PAINT WHITE (-3460 3435);
WIRE 16 -1 (600 4275)(1275 4275);
FORCEPROP 0 LAST SIG_NAME USB_HUB_TEST
J 0
(690 4285);
DISPLAY 0.723404 (690 4285);
PAINT WHITE (690 4285);
WIRE 16 -1 (600 3575)(1325 3575);
FORCEPROP 0 LAST SIG_NAME NC_USB_HUB_DM3
J 0
(740 3585);
DISPLAY 0.723404 (740 3585);
PAINT WHITE (740 3585);
WIRE 16 -1 (600 3525)(1325 3525);
FORCEPROP 0 LAST SIG_NAME NC_USB_HUB_DP4
J 0
(740 3535);
DISPLAY 0.723404 (740 3535);
PAINT WHITE (740 3535);
WIRE 16 -1 (250 175)(1275 175);
FORCEPROP 2 LAST SIG_NAME USB2_HUB_BUF_SWB_R_DN
J 0
(365 185);
DISPLAY 0.723404 (365 185);
PAINT WHITE (365 185);
FORCEPROP 2 LASTPROP $XR0 152 
J 0
(149 185);
DISPLAY 0.638298 (149 185);
PAINT MONO (149 185);
WIRE 16 -1 (-675 -25)(-675 -150);
WIRE 16 -1 (-500 -25)(-675 -25);
FORCEPROP 2 LAST SIG_NAME PD_U5201_EQ
J 0
(-1060 -25);
DISPLAY 0.723404 (-1060 -25);
PAINT WHITE (-1060 -25);
WIRE 16 -1 (-875 2000)(-1450 2000);
FORCEPROP 2 LAST SIG_NAME USB_HUB_OVCUR3
J 0
(-1435 2010);
DISPLAY 0.723404 (-1435 2010);
PAINT WHITE (-1435 2010);
WIRE 16 -1 (-350 3675)(-925 3675);
FORCEPROP 2 LAST SIG_NAME USB_HUB_OVCUR3
J 0
(-910 3685);
DISPLAY 0.723404 (-910 3685);
PAINT WHITE (-910 3685);
WIRE 16 -1 (-350 3725)(-925 3725);
FORCEPROP 2 LAST SIG_NAME USB_HUB_OVCUR2
J 0
(-910 3735);
DISPLAY 0.723404 (-910 3735);
PAINT WHITE (-910 3735);
WIRE 16 -1 (-875 2125)(-1450 2125);
FORCEPROP 2 LAST SIG_NAME USB_HUB_OVCUR2
J 0
(-1435 2135);
DISPLAY 0.723404 (-1435 2135);
PAINT WHITE (-1435 2135);
WIRE 16 -1 (-875 1875)(-1450 1875);
FORCEPROP 2 LAST SIG_NAME USB_HUB_OVCUR4
J 0
(-1435 1885);
DISPLAY 0.723404 (-1435 1885);
PAINT WHITE (-1435 1885);
WIRE 16 -1 (-1375 125)(-500 125);
FORCEPROP 2 LAST SIG_NAME TP_USB2_TEST
J 0
(-1060 135);
DISPLAY 0.723404 (-1060 135);
PAINT WHITE (-1060 135);
DOT 1 (575 900);
DOT 1 (3450 3925);
DOT 1 (-500 4125);
DOT 1 (-500 4075);
DOT 1 (2725 3925);
DOT 1 (4475 4625);
DOT 1 (2825 3875);
DOT 1 (-825 4800);
DOT 1 (-1550 4800);
DOT 1 (-1175 4800);
DOT 1 (-2675 4800);
DOT 1 (-1550 4225);
DOT 1 (-3450 4225);
DOT 1 (-4150 2625);
DOT 1 (-500 4325);
DOT 1 (-500 4025);
DOT 1 (3625 3875);
DOT 1 (-500 4225);
DOT 1 (-1175 4225);
DOT 1 (-1925 4800);
DOT 1 (-1925 4225);
DOT 1 (-2300 4800);
DOT 1 (-2300 4225);
DOT 1 (-2675 4225);
DOT 1 (-3075 4800);
DOT 1 (-3450 4800);
DOT 1 (-3075 4225);
DOT 1 (-1900 3425);
DOT 1 (-1900 3375);
DOT 1 (-2275 2925);
DOT 1 (-2175 2275);
DOT 1 (-2175 2125);
DOT 1 (-2175 2000);
DOT 1 (1125 900);
DOT 1 (575 500);
DOT 1 (-1950 1200);
DOT 1 (-2025 1250);
DOT 1 (-2025 225);
DOT 1 (-1950 175);
DOT 1 (3475 4625);
FORCENOTE
USB_HUB_I2C ONLY FOR EEPROM.
(800 4500) 0;
DISPLAY LEFT (800 4500);
DISPLAY 0.808511 (800 4500);
PAINT WHITE (800 4500);
FORCENOTE
20210527 MODIFY FOR GT
(-4350 5500) 0;
DISPLAY LEFT (-4350 5500);
DISPLAY 2.510638 (-4350 5500);
PAINT PINK (-4350 5500);
FORCENOTE
20220725 CHANGE C2029,C2030 TO 18 PF
(3525 4100) 0;
DISPLAY LEFT (3525 4100);
DISPLAY 0.638298 (3525 4100);
PAINT PINK (3525 4100);
FORCENOTE
$CDS_IMAGE|clipboard_0_7.jpg|1350|1027
(3600 975) 0;
DISPLAY LEFT (3600 975);
QUIT
